(kicad_sch (version 20230121) (generator eeschema)

  (paper "A3")

  (title_block
    (title "Data Center RDIMM DDR4 Tester")
    (date "2024-09-30")
    (rev "1.2.4")
    (company "Antmicro Ltd.")
    (comment 1 "www.antmicro.com")
    (comment 2 "Antmicro Ltd")
  )

  (junction (at 92.71 32.385) (diameter 0) (color 0 0 0 0)
  )
  (junction (at 196.85 152.4) (diameter 0) (color 0 0 0 0)
  )
  (junction (at 255.905 139.7) (diameter 0) (color 0 0 0 0)
  )
  (junction (at 255.905 144.78) (diameter 0) (color 0 0 0 0)
  )
  (junction (at 255.905 142.24) (diameter 0) (color 0 0 0 0)
  )
  (junction (at 115.57 140.335) (diameter 0) (color 0 0 0 0)
  )
  (junction (at 43.18 149.225) (diameter 0) (color 0 0 0 0)
  )
  (junction (at 381.635 199.39) (diameter 0) (color 0 0 0 0)
  )
  (junction (at 212.725 234.95) (diameter 0) (color 0 0 0 0)
  )
  (junction (at 196.85 147.32) (diameter 0) (color 0 0 0 0)
  )
  (junction (at 196.85 154.94) (diameter 0) (color 0 0 0 0)
  )
  (junction (at 327.66 166.37) (diameter 0) (color 0 0 0 0)
  )
  (junction (at 309.245 199.39) (diameter 0) (color 0 0 0 0)
  )
  (junction (at 153.67 219.71) (diameter 0) (color 0 0 0 0)
  )
  (junction (at 43.18 140.97) (diameter 0) (color 0 0 0 0)
  )
  (junction (at 43.18 32.385) (diameter 0) (color 0 0 0 0)
  )
  (junction (at 212.725 232.41) (diameter 0) (color 0 0 0 0)
  )
  (junction (at 196.85 134.62) (diameter 0) (color 0 0 0 0)
  )
  (junction (at 99.06 149.225) (diameter 0) (color 0 0 0 0)
  )
  (junction (at 295.275 199.39) (diameter 0) (color 0 0 0 0)
  )
  (junction (at 167.005 102.87) (diameter 0) (color 0 0 0 0)
  )
  (junction (at 196.85 139.7) (diameter 0) (color 0 0 0 0)
  )
  (junction (at 43.18 41.275) (diameter 0) (color 0 0 0 0)
  )
  (junction (at 273.685 199.39) (diameter 0) (color 0 0 0 0)
  )
  (junction (at 180.34 93.98) (diameter 0) (color 0 0 0 0)
  )
  (junction (at 196.85 144.78) (diameter 0) (color 0 0 0 0)
  )
  (junction (at 357.505 166.37) (diameter 0) (color 0 0 0 0)
  )
  (junction (at 51.435 149.225) (diameter 0) (color 0 0 0 0)
  )
  (junction (at 46.355 88.9) (diameter 0) (color 0 0 0 0)
  )
  (junction (at 46.355 98.425) (diameter 0) (color 0 0 0 0)
  )
  (junction (at 51.435 140.97) (diameter 0) (color 0 0 0 0)
  )
  (junction (at 196.85 142.24) (diameter 0) (color 0 0 0 0)
  )
  (junction (at 59.69 41.275) (diameter 0) (color 0 0 0 0)
  )
  (junction (at 111.76 88.9) (diameter 0) (color 0 0 0 0)
  )
  (junction (at 200.025 199.39) (diameter 0) (color 0 0 0 0)
  )
  (junction (at 34.925 149.225) (diameter 0) (color 0 0 0 0)
  )
  (junction (at 103.505 97.155) (diameter 0) (color 0 0 0 0)
  )
  (junction (at 180.34 102.87) (diameter 0) (color 0 0 0 0)
  )
  (junction (at 238.125 199.39) (diameter 0) (color 0 0 0 0)
  )
  (junction (at 357.505 157.48) (diameter 0) (color 0 0 0 0)
  )
  (junction (at 59.69 140.97) (diameter 0) (color 0 0 0 0)
  )
  (junction (at 386.715 214.63) (diameter 0) (color 0 0 0 0)
  )
  (junction (at 225.425 229.87) (diameter 0) (color 0 0 0 0)
  )
  (junction (at 255.905 152.4) (diameter 0) (color 0 0 0 0)
  )
  (junction (at 167.005 93.98) (diameter 0) (color 0 0 0 0)
  )
  (junction (at 234.315 199.39) (diameter 0) (color 0 0 0 0)
  )
  (junction (at 342.9 157.48) (diameter 0) (color 0 0 0 0)
  )
  (junction (at 332.74 92.71) (diameter 0) (color 0 0 0 0)
  )
  (junction (at 176.53 199.39) (diameter 0) (color 0 0 0 0)
  )
  (junction (at 376.555 214.63) (diameter 0) (color 0 0 0 0)
  )
  (junction (at 76.2 41.275) (diameter 0) (color 0 0 0 0)
  )
  (junction (at 196.85 137.16) (diameter 0) (color 0 0 0 0)
  )
  (junction (at 173.99 111.125) (diameter 0) (color 0 0 0 0)
  )
  (junction (at 255.905 147.32) (diameter 0) (color 0 0 0 0)
  )
  (junction (at 38.1 98.425) (diameter 0) (color 0 0 0 0)
  )
  (junction (at 302.26 199.39) (diameter 0) (color 0 0 0 0)
  )
  (junction (at 205.105 199.39) (diameter 0) (color 0 0 0 0)
  )
  (junction (at 255.905 154.94) (diameter 0) (color 0 0 0 0)
  )
  (junction (at 318.135 199.39) (diameter 0) (color 0 0 0 0)
  )
  (junction (at 84.455 41.275) (diameter 0) (color 0 0 0 0)
  )
  (junction (at 196.85 157.48) (diameter 0) (color 0 0 0 0)
  )
  (junction (at 320.04 166.37) (diameter 0) (color 0 0 0 0)
  )
  (junction (at 365.125 166.37) (diameter 0) (color 0 0 0 0)
  )
  (junction (at 212.725 229.87) (diameter 0) (color 0 0 0 0)
  )
  (junction (at 196.85 149.86) (diameter 0) (color 0 0 0 0)
  )
  (junction (at 107.315 149.225) (diameter 0) (color 0 0 0 0)
  )
  (junction (at 67.945 41.275) (diameter 0) (color 0 0 0 0)
  )
  (junction (at 107.315 140.335) (diameter 0) (color 0 0 0 0)
  )
  (junction (at 38.1 88.9) (diameter 0) (color 0 0 0 0)
  )
  (junction (at 349.885 157.48) (diameter 0) (color 0 0 0 0)
  )
  (junction (at 236.22 93.98) (diameter 0) (color 0 0 0 0)
  )
  (junction (at 51.435 32.385) (diameter 0) (color 0 0 0 0)
  )
  (junction (at 320.04 157.48) (diameter 0) (color 0 0 0 0)
  )
  (junction (at 84.455 32.385) (diameter 0) (color 0 0 0 0)
  )
  (junction (at 255.905 149.86) (diameter 0) (color 0 0 0 0)
  )
  (junction (at 54.61 88.9) (diameter 0) (color 0 0 0 0)
  )
  (junction (at 349.885 166.37) (diameter 0) (color 0 0 0 0)
  )
  (junction (at 327.66 157.48) (diameter 0) (color 0 0 0 0)
  )
  (junction (at 200.025 229.87) (diameter 0) (color 0 0 0 0)
  )
  (junction (at 100.965 41.275) (diameter 0) (color 0 0 0 0)
  )
  (junction (at 100.965 32.385) (diameter 0) (color 0 0 0 0)
  )
  (junction (at 103.505 88.9) (diameter 0) (color 0 0 0 0)
  )
  (junction (at 120.015 88.9) (diameter 0) (color 0 0 0 0)
  )
  (junction (at 34.925 140.97) (diameter 0) (color 0 0 0 0)
  )
  (junction (at 376.555 199.39) (diameter 0) (color 0 0 0 0)
  )
  (junction (at 59.69 32.385) (diameter 0) (color 0 0 0 0)
  )
  (junction (at 321.945 30.48) (diameter 0) (color 0 0 0 0)
  )
  (junction (at 236.22 91.44) (diameter 0) (color 0 0 0 0)
  )
  (junction (at 281.305 199.39) (diameter 0) (color 0 0 0 0)
  )
  (junction (at 332.74 90.17) (diameter 0) (color 0 0 0 0)
  )
  (junction (at 365.125 157.48) (diameter 0) (color 0 0 0 0)
  )
  (junction (at 67.945 32.385) (diameter 0) (color 0 0 0 0)
  )
  (junction (at 238.125 229.87) (diameter 0) (color 0 0 0 0)
  )
  (junction (at 255.905 137.16) (diameter 0) (color 0 0 0 0)
  )
  (junction (at 386.715 199.39) (diameter 0) (color 0 0 0 0)
  )
  (junction (at 335.28 166.37) (diameter 0) (color 0 0 0 0)
  )
  (junction (at 266.065 199.39) (diameter 0) (color 0 0 0 0)
  )
  (junction (at 33.02 242.57) (diameter 0) (color 0 0 0 0)
  )
  (junction (at 76.2 32.385) (diameter 0) (color 0 0 0 0)
  )
  (junction (at 29.845 88.9) (diameter 0) (color 0 0 0 0)
  )
  (junction (at 205.105 229.87) (diameter 0) (color 0 0 0 0)
  )
  (junction (at 29.845 98.425) (diameter 0) (color 0 0 0 0)
  )
  (junction (at 262.255 242.57) (diameter 0) (color 0 0 0 0)
  )
  (junction (at 227.965 229.87) (diameter 0) (color 0 0 0 0)
  )
  (junction (at 111.76 97.155) (diameter 0) (color 0 0 0 0)
  )
  (junction (at 335.28 157.48) (diameter 0) (color 0 0 0 0)
  )
  (junction (at 381.635 214.63) (diameter 0) (color 0 0 0 0)
  )
  (junction (at 99.06 140.335) (diameter 0) (color 0 0 0 0)
  )
  (junction (at 342.9 166.37) (diameter 0) (color 0 0 0 0)
  )
  (junction (at 51.435 41.275) (diameter 0) (color 0 0 0 0)
  )
  (junction (at 238.125 227.33) (diameter 0) (color 0 0 0 0)
  )
  (junction (at 92.71 41.275) (diameter 0) (color 0 0 0 0)
  )
  (junction (at 90.805 219.075) (diameter 0) (color 0 0 0 0)
  )
  (junction (at 54.61 98.425) (diameter 0) (color 0 0 0 0)
  )

  (no_connect (at 239.395 242.57))
  (no_connect (at 361.315 50.8))
  (no_connect (at 361.315 87.63))
  (no_connect (at 234.315 43.18))
  (no_connect (at 363.855 207.01))

  (wire (pts (xy 386.715 211.455) (xy 386.715 214.63))
    (stroke (width 0) (type default))
  )
  (wire (pts (xy 180.34 111.125) (xy 173.99 111.125))
    (stroke (width 0) (type default))
  )
  (wire (pts (xy 43.18 147.955) (xy 43.18 149.225))
    (stroke (width 0) (type default))
  )
  (wire (pts (xy 317.5 113.03) (xy 332.105 113.03))
    (stroke (width 0) (type default))
  )
  (wire (pts (xy 189.865 38.1) (xy 177.8 38.1))
    (stroke (width 0) (type default))
  )
  (wire (pts (xy 185.42 137.16) (xy 196.85 137.16))
    (stroke (width 0) (type default))
  )
  (wire (pts (xy 33.02 240.665) (xy 33.02 242.57))
    (stroke (width 0) (type default))
  )
  (wire (pts (xy 251.46 63.5) (xy 234.315 63.5))
    (stroke (width 0) (type default))
  )
  (wire (pts (xy 245.11 139.7) (xy 255.905 139.7))
    (stroke (width 0) (type default))
  )
  (wire (pts (xy 227.965 226.695) (xy 227.965 229.87))
    (stroke (width 0) (type default))
  )
  (wire (pts (xy 77.47 237.49) (xy 96.52 237.49))
    (stroke (width 0) (type default))
  )
  (wire (pts (xy 323.85 53.34) (xy 334.645 53.34))
    (stroke (width 0) (type default))
  )
  (wire (pts (xy 185.42 139.7) (xy 196.85 139.7))
    (stroke (width 0) (type default))
  )
  (wire (pts (xy 200.025 229.87) (xy 205.105 229.87))
    (stroke (width 0) (type default))
  )
  (wire (pts (xy 332.74 92.71) (xy 334.645 92.71))
    (stroke (width 0) (type default))
  )
  (wire (pts (xy 361.315 73.66) (xy 377.19 73.66))
    (stroke (width 0) (type default))
  )
  (wire (pts (xy 386.715 214.63) (xy 386.715 215.9))
    (stroke (width 0) (type default))
  )
  (wire (pts (xy 332.74 90.17) (xy 332.74 92.71))
    (stroke (width 0) (type default))
  )
  (wire (pts (xy 251.46 40.64) (xy 234.315 40.64))
    (stroke (width 0) (type default))
  )
  (wire (pts (xy 115.57 140.335) (xy 107.315 140.335))
    (stroke (width 0) (type default))
  )
  (wire (pts (xy 186.69 34.29) (xy 189.865 34.29))
    (stroke (width 0) (type default))
  )
  (wire (pts (xy 234.315 207.645) (xy 234.315 212.09))
    (stroke (width 0) (type default))
  )
  (wire (pts (xy 317.5 133.985) (xy 332.105 133.985))
    (stroke (width 0) (type default))
  )
  (wire (pts (xy 111.76 97.155) (xy 103.505 97.155))
    (stroke (width 0) (type default))
  )
  (wire (pts (xy 43.18 212.09) (xy 55.88 212.09))
    (stroke (width 0) (type default))
  )
  (wire (pts (xy 55.88 234.95) (xy 46.355 234.95))
    (stroke (width 0) (type default))
  )
  (wire (pts (xy 189.865 57.15) (xy 188.595 57.15))
    (stroke (width 0) (type default))
  )
  (wire (pts (xy 196.85 134.62) (xy 196.85 137.16))
    (stroke (width 0) (type default))
  )
  (wire (pts (xy 238.125 199.39) (xy 238.125 209.55))
    (stroke (width 0) (type default))
  )
  (wire (pts (xy 231.14 154.94) (xy 240.03 154.94))
    (stroke (width 0) (type default))
  )
  (wire (pts (xy 38.1 88.9) (xy 38.1 91.44))
    (stroke (width 0) (type default))
  )
  (wire (pts (xy 167.005 111.125) (xy 167.005 109.22))
    (stroke (width 0) (type default))
  )
  (wire (pts (xy 295.275 199.39) (xy 295.275 208.915))
    (stroke (width 0) (type default))
  )
  (wire (pts (xy 315.595 157.48) (xy 320.04 157.48))
    (stroke (width 0) (type default))
  )
  (wire (pts (xy 34.925 142.875) (xy 34.925 140.97))
    (stroke (width 0) (type default))
  )
  (wire (pts (xy 361.315 90.17) (xy 377.19 90.17))
    (stroke (width 0) (type default))
  )
  (wire (pts (xy 260.985 240.03) (xy 262.255 240.03))
    (stroke (width 0) (type default))
  )
  (wire (pts (xy 363.22 133.985) (xy 378.46 133.985))
    (stroke (width 0) (type default))
  )
  (wire (pts (xy 227.965 219.71) (xy 239.395 219.71))
    (stroke (width 0) (type default))
  )
  (wire (pts (xy 205.105 199.39) (xy 205.105 208.915))
    (stroke (width 0) (type default))
  )
  (wire (pts (xy 357.505 166.37) (xy 365.125 166.37))
    (stroke (width 0) (type default))
  )
  (wire (pts (xy 376.555 199.39) (xy 381.635 199.39))
    (stroke (width 0) (type default))
  )
  (wire (pts (xy 187.96 41.91) (xy 189.865 41.91))
    (stroke (width 0) (type default))
  )
  (wire (pts (xy 238.125 227.33) (xy 238.125 229.87))
    (stroke (width 0) (type default))
  )
  (wire (pts (xy 363.855 214.63) (xy 376.555 214.63))
    (stroke (width 0) (type default))
  )
  (wire (pts (xy 76.2 40.005) (xy 76.2 41.275))
    (stroke (width 0) (type default))
  )
  (wire (pts (xy 337.185 144.78) (xy 358.14 144.78))
    (stroke (width 0) (type default))
  )
  (wire (pts (xy 349.885 165.1) (xy 349.885 166.37))
    (stroke (width 0) (type default))
  )
  (wire (pts (xy 372.11 165.1) (xy 372.11 166.37))
    (stroke (width 0) (type default))
  )
  (wire (pts (xy 376.555 211.455) (xy 376.555 214.63))
    (stroke (width 0) (type default))
  )
  (wire (pts (xy 120.015 88.9) (xy 120.015 90.805))
    (stroke (width 0) (type default))
  )
  (wire (pts (xy 320.04 165.1) (xy 320.04 166.37))
    (stroke (width 0) (type default))
  )
  (wire (pts (xy 309.245 199.39) (xy 309.245 208.915))
    (stroke (width 0) (type default))
  )
  (wire (pts (xy 34.925 149.225) (xy 34.925 151.13))
    (stroke (width 0) (type default))
  )
  (wire (pts (xy 167.005 93.98) (xy 167.005 91.44))
    (stroke (width 0) (type default))
  )
  (wire (pts (xy 59.69 40.005) (xy 59.69 41.275))
    (stroke (width 0) (type default))
  )
  (wire (pts (xy 251.46 69.85) (xy 234.315 69.85))
    (stroke (width 0) (type default))
  )
  (wire (pts (xy 172.085 137.16) (xy 180.34 137.16))
    (stroke (width 0) (type default))
  )
  (wire (pts (xy 173.99 199.39) (xy 176.53 199.39))
    (stroke (width 0) (type default))
  )
  (wire (pts (xy 349.885 166.37) (xy 357.505 166.37))
    (stroke (width 0) (type default))
  )
  (wire (pts (xy 153.67 199.39) (xy 153.67 219.71))
    (stroke (width 0) (type default))
  )
  (wire (pts (xy 38.1 98.425) (xy 29.845 98.425))
    (stroke (width 0) (type default))
  )
  (wire (pts (xy 225.425 232.41) (xy 239.395 232.41))
    (stroke (width 0) (type default))
  )
  (wire (pts (xy 364.49 38.1) (xy 361.315 38.1))
    (stroke (width 0) (type default))
  )
  (wire (pts (xy 364.49 44.45) (xy 361.315 44.45))
    (stroke (width 0) (type default))
  )
  (wire (pts (xy 266.065 199.39) (xy 266.065 201.93))
    (stroke (width 0) (type default))
  )
  (wire (pts (xy 99.06 147.955) (xy 99.06 149.225))
    (stroke (width 0) (type default))
  )
  (wire (pts (xy 185.42 142.24) (xy 196.85 142.24))
    (stroke (width 0) (type default))
  )
  (wire (pts (xy 323.85 58.42) (xy 334.645 58.42))
    (stroke (width 0) (type default))
  )
  (wire (pts (xy 231.14 144.78) (xy 240.03 144.78))
    (stroke (width 0) (type default))
  )
  (wire (pts (xy 143.51 214.63) (xy 156.21 214.63))
    (stroke (width 0) (type default))
  )
  (wire (pts (xy 251.46 60.96) (xy 234.315 60.96))
    (stroke (width 0) (type default))
  )
  (wire (pts (xy 196.85 154.94) (xy 196.85 157.48))
    (stroke (width 0) (type default))
  )
  (wire (pts (xy 245.11 142.24) (xy 255.905 142.24))
    (stroke (width 0) (type default))
  )
  (wire (pts (xy 327.66 157.48) (xy 327.66 160.02))
    (stroke (width 0) (type default))
  )
  (polyline (pts (xy 12.7 118.745) (xy 139.7 118.745))
    (stroke (width 0) (type default))
  )

  (wire (pts (xy 357.505 157.48) (xy 365.125 157.48))
    (stroke (width 0) (type default))
  )
  (wire (pts (xy 318.135 199.39) (xy 343.535 199.39))
    (stroke (width 0) (type default))
  )
  (wire (pts (xy 92.71 140.335) (xy 91.44 140.335))
    (stroke (width 0) (type default))
  )
  (wire (pts (xy 335.28 165.1) (xy 335.28 166.37))
    (stroke (width 0) (type default))
  )
  (wire (pts (xy 76.2 32.385) (xy 76.2 34.925))
    (stroke (width 0) (type default))
  )
  (wire (pts (xy 180.34 157.48) (xy 172.085 157.48))
    (stroke (width 0) (type default))
  )
  (wire (pts (xy 188.595 76.2) (xy 189.865 76.2))
    (stroke (width 0) (type default))
  )
  (wire (pts (xy 334.01 237.49) (xy 334.01 238.76))
    (stroke (width 0) (type default))
  )
  (wire (pts (xy 295.275 199.39) (xy 302.26 199.39))
    (stroke (width 0) (type default))
  )
  (wire (pts (xy 29.845 88.9) (xy 29.845 91.44))
    (stroke (width 0) (type default))
  )
  (wire (pts (xy 364.49 53.34) (xy 361.315 53.34))
    (stroke (width 0) (type default))
  )
  (wire (pts (xy 343.535 214.63) (xy 342.265 214.63))
    (stroke (width 0) (type default))
  )
  (wire (pts (xy 180.34 147.32) (xy 172.085 147.32))
    (stroke (width 0) (type default))
  )
  (wire (pts (xy 327.66 157.48) (xy 335.28 157.48))
    (stroke (width 0) (type default))
  )
  (wire (pts (xy 372.11 157.48) (xy 372.11 160.02))
    (stroke (width 0) (type default))
  )
  (wire (pts (xy 245.11 152.4) (xy 255.905 152.4))
    (stroke (width 0) (type default))
  )
  (wire (pts (xy 212.725 232.41) (xy 212.725 229.87))
    (stroke (width 0) (type default))
  )
  (wire (pts (xy 87.63 219.075) (xy 90.805 219.075))
    (stroke (width 0) (type default))
  )
  (wire (pts (xy 381.635 199.39) (xy 386.715 199.39))
    (stroke (width 0) (type default))
  )
  (wire (pts (xy 328.295 25.4) (xy 334.645 25.4))
    (stroke (width 0) (type default))
  )
  (wire (pts (xy 225.425 234.95) (xy 239.395 234.95))
    (stroke (width 0) (type default))
  )
  (polyline (pts (xy 139.7 118.745) (xy 139.7 119.38))
    (stroke (width 0) (type default))
  )

  (wire (pts (xy 327.66 165.1) (xy 327.66 166.37))
    (stroke (width 0) (type default))
  )
  (wire (pts (xy 115.57 140.335) (xy 123.825 140.335))
    (stroke (width 0) (type default))
  )
  (wire (pts (xy 273.685 199.39) (xy 273.685 201.93))
    (stroke (width 0) (type default))
  )
  (wire (pts (xy 173.99 107.95) (xy 173.99 111.125))
    (stroke (width 0) (type default))
  )
  (wire (pts (xy 103.505 97.155) (xy 103.505 99.06))
    (stroke (width 0) (type default))
  )
  (wire (pts (xy 107.315 140.335) (xy 99.06 140.335))
    (stroke (width 0) (type default))
  )
  (wire (pts (xy 26.035 88.9) (xy 29.845 88.9))
    (stroke (width 0) (type default))
  )
  (wire (pts (xy 185.42 144.78) (xy 196.85 144.78))
    (stroke (width 0) (type default))
  )
  (wire (pts (xy 381.635 214.63) (xy 386.715 214.63))
    (stroke (width 0) (type default))
  )
  (wire (pts (xy 306.705 30.48) (xy 312.42 30.48))
    (stroke (width 0) (type default))
  )
  (wire (pts (xy 317.5 136.525) (xy 332.105 136.525))
    (stroke (width 0) (type default))
  )
  (wire (pts (xy 189.865 78.74) (xy 188.595 78.74))
    (stroke (width 0) (type default))
  )
  (wire (pts (xy 200.025 215.265) (xy 200.025 229.87))
    (stroke (width 0) (type default))
  )
  (wire (pts (xy 262.255 240.03) (xy 262.255 242.57))
    (stroke (width 0) (type default))
  )
  (wire (pts (xy 255.905 144.78) (xy 255.905 147.32))
    (stroke (width 0) (type default))
  )
  (wire (pts (xy 99.06 140.335) (xy 97.79 140.335))
    (stroke (width 0) (type default))
  )
  (wire (pts (xy 335.28 166.37) (xy 342.9 166.37))
    (stroke (width 0) (type default))
  )
  (wire (pts (xy 260.985 234.95) (xy 272.415 234.95))
    (stroke (width 0) (type default))
  )
  (wire (pts (xy 227.965 219.71) (xy 227.965 221.615))
    (stroke (width 0) (type default))
  )
  (wire (pts (xy 93.98 219.075) (xy 93.98 221.615))
    (stroke (width 0) (type default))
  )
  (wire (pts (xy 51.435 140.97) (xy 43.18 140.97))
    (stroke (width 0) (type default))
  )
  (wire (pts (xy 120.015 97.155) (xy 111.76 97.155))
    (stroke (width 0) (type default))
  )
  (wire (pts (xy 320.04 166.37) (xy 320.04 167.64))
    (stroke (width 0) (type default))
  )
  (wire (pts (xy 76.2 41.275) (xy 67.945 41.275))
    (stroke (width 0) (type default))
  )
  (wire (pts (xy 188.595 81.28) (xy 189.865 81.28))
    (stroke (width 0) (type default))
  )
  (wire (pts (xy 185.42 157.48) (xy 196.85 157.48))
    (stroke (width 0) (type default))
  )
  (wire (pts (xy 364.49 55.88) (xy 361.315 55.88))
    (stroke (width 0) (type default))
  )
  (wire (pts (xy 100.965 41.275) (xy 92.71 41.275))
    (stroke (width 0) (type default))
  )
  (wire (pts (xy 191.77 199.39) (xy 200.025 199.39))
    (stroke (width 0) (type default))
  )
  (wire (pts (xy 225.425 229.87) (xy 227.965 229.87))
    (stroke (width 0) (type default))
  )
  (wire (pts (xy 43.18 222.25) (xy 55.88 222.25))
    (stroke (width 0) (type default))
  )
  (wire (pts (xy 363.22 147.32) (xy 378.46 147.32))
    (stroke (width 0) (type default))
  )
  (wire (pts (xy 189.865 73.66) (xy 188.595 73.66))
    (stroke (width 0) (type default))
  )
  (wire (pts (xy 235.585 78.74) (xy 234.315 78.74))
    (stroke (width 0) (type default))
  )
  (wire (pts (xy 167.005 111.125) (xy 173.99 111.125))
    (stroke (width 0) (type default))
  )
  (wire (pts (xy 234.315 212.09) (xy 239.395 212.09))
    (stroke (width 0) (type default))
  )
  (wire (pts (xy 306.705 33.02) (xy 312.42 33.02))
    (stroke (width 0) (type default))
  )
  (wire (pts (xy 281.305 199.39) (xy 281.305 201.93))
    (stroke (width 0) (type default))
  )
  (wire (pts (xy 153.67 219.71) (xy 156.21 219.71))
    (stroke (width 0) (type default))
  )
  (wire (pts (xy 359.41 233.68) (xy 372.11 233.68))
    (stroke (width 0) (type default))
  )
  (wire (pts (xy 364.49 27.94) (xy 361.315 27.94))
    (stroke (width 0) (type default))
  )
  (wire (pts (xy 386.715 199.39) (xy 389.89 199.39))
    (stroke (width 0) (type default))
  )
  (wire (pts (xy 273.685 207.01) (xy 273.685 212.09))
    (stroke (width 0) (type default))
  )
  (wire (pts (xy 111.76 88.9) (xy 111.76 90.805))
    (stroke (width 0) (type default))
  )
  (wire (pts (xy 363.22 144.78) (xy 378.46 144.78))
    (stroke (width 0) (type default))
  )
  (wire (pts (xy 185.42 154.94) (xy 196.85 154.94))
    (stroke (width 0) (type default))
  )
  (wire (pts (xy 320.04 166.37) (xy 327.66 166.37))
    (stroke (width 0) (type default))
  )
  (wire (pts (xy 54.61 96.52) (xy 54.61 98.425))
    (stroke (width 0) (type default))
  )
  (wire (pts (xy 62.865 88.9) (xy 54.61 88.9))
    (stroke (width 0) (type default))
  )
  (wire (pts (xy 251.46 67.31) (xy 234.315 67.31))
    (stroke (width 0) (type default))
  )
  (wire (pts (xy 323.85 35.56) (xy 334.645 35.56))
    (stroke (width 0) (type default))
  )
  (wire (pts (xy 361.315 67.31) (xy 377.19 67.31))
    (stroke (width 0) (type default))
  )
  (wire (pts (xy 245.11 134.62) (xy 255.905 134.62))
    (stroke (width 0) (type default))
  )
  (polyline (pts (xy 12.065 66.04) (xy 139.7 66.04))
    (stroke (width 0) (type default))
  )

  (wire (pts (xy 185.42 149.86) (xy 196.85 149.86))
    (stroke (width 0) (type default))
  )
  (wire (pts (xy 59.69 140.97) (xy 67.945 140.97))
    (stroke (width 0) (type default))
  )
  (wire (pts (xy 302.26 199.39) (xy 302.26 208.915))
    (stroke (width 0) (type default))
  )
  (wire (pts (xy 361.315 80.01) (xy 377.19 80.01))
    (stroke (width 0) (type default))
  )
  (wire (pts (xy 43.18 140.97) (xy 43.18 142.875))
    (stroke (width 0) (type default))
  )
  (wire (pts (xy 236.22 93.98) (xy 236.22 95.885))
    (stroke (width 0) (type default))
  )
  (wire (pts (xy 251.46 38.1) (xy 234.315 38.1))
    (stroke (width 0) (type default))
  )
  (wire (pts (xy 361.315 82.55) (xy 377.19 82.55))
    (stroke (width 0) (type default))
  )
  (wire (pts (xy 55.88 232.41) (xy 36.83 232.41))
    (stroke (width 0) (type default))
  )
  (wire (pts (xy 51.435 32.385) (xy 43.18 32.385))
    (stroke (width 0) (type default))
  )
  (wire (pts (xy 255.905 142.24) (xy 255.905 144.78))
    (stroke (width 0) (type default))
  )
  (wire (pts (xy 231.14 137.16) (xy 240.03 137.16))
    (stroke (width 0) (type default))
  )
  (wire (pts (xy 185.42 152.4) (xy 196.85 152.4))
    (stroke (width 0) (type default))
  )
  (wire (pts (xy 43.18 214.63) (xy 55.88 214.63))
    (stroke (width 0) (type default))
  )
  (wire (pts (xy 239.395 224.79) (xy 238.125 224.79))
    (stroke (width 0) (type default))
  )
  (wire (pts (xy 59.69 41.275) (xy 51.435 41.275))
    (stroke (width 0) (type default))
  )
  (wire (pts (xy 328.295 80.01) (xy 334.645 80.01))
    (stroke (width 0) (type default))
  )
  (wire (pts (xy 54.61 98.425) (xy 62.865 98.425))
    (stroke (width 0) (type default))
  )
  (wire (pts (xy 357.505 157.48) (xy 357.505 160.02))
    (stroke (width 0) (type default))
  )
  (wire (pts (xy 240.03 139.7) (xy 231.14 139.7))
    (stroke (width 0) (type default))
  )
  (wire (pts (xy 51.435 41.275) (xy 43.18 41.275))
    (stroke (width 0) (type default))
  )
  (wire (pts (xy 107.315 147.955) (xy 107.315 149.225))
    (stroke (width 0) (type default))
  )
  (wire (pts (xy 212.725 229.87) (xy 225.425 229.87))
    (stroke (width 0) (type default))
  )
  (wire (pts (xy 205.105 229.87) (xy 212.725 229.87))
    (stroke (width 0) (type default))
  )
  (polyline (pts (xy 12.065 175.26) (xy 408.94 175.26))
    (stroke (width 0) (type default))
  )

  (wire (pts (xy 255.905 152.4) (xy 255.905 154.94))
    (stroke (width 0) (type default))
  )
  (wire (pts (xy 100.965 32.385) (xy 100.965 34.925))
    (stroke (width 0) (type default))
  )
  (wire (pts (xy 238.125 229.87) (xy 239.395 229.87))
    (stroke (width 0) (type default))
  )
  (wire (pts (xy 342.9 165.1) (xy 342.9 166.37))
    (stroke (width 0) (type default))
  )
  (wire (pts (xy 187.96 87.63) (xy 189.865 87.63))
    (stroke (width 0) (type default))
  )
  (wire (pts (xy 251.46 50.8) (xy 234.315 50.8))
    (stroke (width 0) (type default))
  )
  (wire (pts (xy 297.815 147.32) (xy 313.055 147.32))
    (stroke (width 0) (type default))
  )
  (wire (pts (xy 51.435 40.005) (xy 51.435 41.275))
    (stroke (width 0) (type default))
  )
  (wire (pts (xy 317.5 110.49) (xy 332.105 110.49))
    (stroke (width 0) (type default))
  )
  (wire (pts (xy 173.99 111.125) (xy 173.99 113.03))
    (stroke (width 0) (type default))
  )
  (wire (pts (xy 143.51 204.47) (xy 156.21 204.47))
    (stroke (width 0) (type default))
  )
  (wire (pts (xy 167.005 104.14) (xy 167.005 102.87))
    (stroke (width 0) (type default))
  )
  (wire (pts (xy 120.015 95.885) (xy 120.015 97.155))
    (stroke (width 0) (type default))
  )
  (wire (pts (xy 363.22 136.525) (xy 378.46 136.525))
    (stroke (width 0) (type default))
  )
  (wire (pts (xy 172.085 160.02) (xy 180.34 160.02))
    (stroke (width 0) (type default))
  )
  (wire (pts (xy 93.98 88.9) (xy 90.17 88.9))
    (stroke (width 0) (type default))
  )
  (wire (pts (xy 364.49 31.75) (xy 361.315 31.75))
    (stroke (width 0) (type default))
  )
  (wire (pts (xy 363.22 122.555) (xy 378.46 122.555))
    (stroke (width 0) (type default))
  )
  (wire (pts (xy 189.865 50.8) (xy 188.595 50.8))
    (stroke (width 0) (type default))
  )
  (wire (pts (xy 143.51 224.79) (xy 156.21 224.79))
    (stroke (width 0) (type default))
  )
  (wire (pts (xy 109.22 32.385) (xy 109.22 34.925))
    (stroke (width 0) (type default))
  )
  (polyline (pts (xy 140.335 175.26) (xy 140.335 12.7))
    (stroke (width 0) (type default))
  )

  (wire (pts (xy 167.005 102.87) (xy 170.18 102.87))
    (stroke (width 0) (type default))
  )
  (wire (pts (xy 270.51 229.87) (xy 283.21 229.87))
    (stroke (width 0) (type default))
  )
  (wire (pts (xy 200.025 199.39) (xy 205.105 199.39))
    (stroke (width 0) (type default))
  )
  (wire (pts (xy 337.185 147.32) (xy 358.14 147.32))
    (stroke (width 0) (type default))
  )
  (wire (pts (xy 337.185 113.03) (xy 358.14 113.03))
    (stroke (width 0) (type default))
  )
  (wire (pts (xy 172.085 144.78) (xy 180.34 144.78))
    (stroke (width 0) (type default))
  )
  (wire (pts (xy 245.11 137.16) (xy 255.905 137.16))
    (stroke (width 0) (type default))
  )
  (wire (pts (xy 77.47 234.95) (xy 93.98 234.95))
    (stroke (width 0) (type default))
  )
  (wire (pts (xy 92.71 40.005) (xy 92.71 41.275))
    (stroke (width 0) (type default))
  )
  (wire (pts (xy 201.295 134.62) (xy 196.85 134.62))
    (stroke (width 0) (type default))
  )
  (wire (pts (xy 77.47 229.87) (xy 90.805 229.87))
    (stroke (width 0) (type default))
  )
  (wire (pts (xy 262.255 242.57) (xy 262.255 243.84))
    (stroke (width 0) (type default))
  )
  (wire (pts (xy 93.98 234.95) (xy 93.98 226.695))
    (stroke (width 0) (type default))
  )
  (wire (pts (xy 346.71 233.68) (xy 334.01 233.68))
    (stroke (width 0) (type default))
  )
  (wire (pts (xy 225.425 217.17) (xy 239.395 217.17))
    (stroke (width 0) (type default))
  )
  (wire (pts (xy 349.885 157.48) (xy 357.505 157.48))
    (stroke (width 0) (type default))
  )
  (wire (pts (xy 323.85 45.72) (xy 334.645 45.72))
    (stroke (width 0) (type default))
  )
  (wire (pts (xy 51.435 147.955) (xy 51.435 149.225))
    (stroke (width 0) (type default))
  )
  (wire (pts (xy 43.18 32.385) (xy 43.18 34.925))
    (stroke (width 0) (type default))
  )
  (wire (pts (xy 196.85 157.48) (xy 196.85 160.02))
    (stroke (width 0) (type default))
  )
  (wire (pts (xy 172.085 142.24) (xy 180.34 142.24))
    (stroke (width 0) (type default))
  )
  (wire (pts (xy 238.125 199.39) (xy 266.065 199.39))
    (stroke (width 0) (type default))
  )
  (wire (pts (xy 33.02 242.57) (xy 36.83 242.57))
    (stroke (width 0) (type default))
  )
  (wire (pts (xy 43.18 32.385) (xy 40.005 32.385))
    (stroke (width 0) (type default))
  )
  (wire (pts (xy 92.71 32.385) (xy 92.71 34.925))
    (stroke (width 0) (type default))
  )
  (wire (pts (xy 38.1 88.9) (xy 29.845 88.9))
    (stroke (width 0) (type default))
  )
  (wire (pts (xy 335.28 157.48) (xy 342.9 157.48))
    (stroke (width 0) (type default))
  )
  (wire (pts (xy 180.34 152.4) (xy 172.085 152.4))
    (stroke (width 0) (type default))
  )
  (wire (pts (xy 365.125 166.37) (xy 372.11 166.37))
    (stroke (width 0) (type default))
  )
  (wire (pts (xy 189.865 67.31) (xy 188.595 67.31))
    (stroke (width 0) (type default))
  )
  (wire (pts (xy 266.065 199.39) (xy 273.685 199.39))
    (stroke (width 0) (type default))
  )
  (wire (pts (xy 84.455 32.385) (xy 84.455 34.925))
    (stroke (width 0) (type default))
  )
  (wire (pts (xy 364.49 25.4) (xy 361.315 25.4))
    (stroke (width 0) (type default))
  )
  (wire (pts (xy 225.425 237.49) (xy 239.395 237.49))
    (stroke (width 0) (type default))
  )
  (wire (pts (xy 205.105 199.39) (xy 234.315 199.39))
    (stroke (width 0) (type default))
  )
  (wire (pts (xy 43.18 207.01) (xy 55.88 207.01))
    (stroke (width 0) (type default))
  )
  (wire (pts (xy 255.905 134.62) (xy 255.905 137.16))
    (stroke (width 0) (type default))
  )
  (wire (pts (xy 51.435 142.875) (xy 51.435 140.97))
    (stroke (width 0) (type default))
  )
  (wire (pts (xy 84.455 40.005) (xy 84.455 41.275))
    (stroke (width 0) (type default))
  )
  (wire (pts (xy 273.685 199.39) (xy 281.305 199.39))
    (stroke (width 0) (type default))
  )
  (wire (pts (xy 297.815 144.78) (xy 313.055 144.78))
    (stroke (width 0) (type default))
  )
  (wire (pts (xy 337.185 133.985) (xy 358.14 133.985))
    (stroke (width 0) (type default))
  )
  (wire (pts (xy 236.22 91.44) (xy 236.22 93.98))
    (stroke (width 0) (type default))
  )
  (wire (pts (xy 266.065 207.01) (xy 266.065 209.55))
    (stroke (width 0) (type default))
  )
  (wire (pts (xy 109.22 40.005) (xy 109.22 41.275))
    (stroke (width 0) (type default))
  )
  (wire (pts (xy 103.505 95.885) (xy 103.505 97.155))
    (stroke (width 0) (type default))
  )
  (wire (pts (xy 46.355 88.9) (xy 46.355 91.44))
    (stroke (width 0) (type default))
  )
  (wire (pts (xy 337.185 136.525) (xy 358.14 136.525))
    (stroke (width 0) (type default))
  )
  (wire (pts (xy 231.14 142.24) (xy 240.03 142.24))
    (stroke (width 0) (type default))
  )
  (wire (pts (xy 196.85 142.24) (xy 196.85 144.78))
    (stroke (width 0) (type default))
  )
  (wire (pts (xy 99.06 149.225) (xy 99.06 150.495))
    (stroke (width 0) (type default))
  )
  (wire (pts (xy 153.67 219.71) (xy 153.67 229.87))
    (stroke (width 0) (type default))
  )
  (wire (pts (xy 255.905 147.32) (xy 255.905 149.86))
    (stroke (width 0) (type default))
  )
  (wire (pts (xy 46.355 96.52) (xy 46.355 98.425))
    (stroke (width 0) (type default))
  )
  (wire (pts (xy 55.88 240.03) (xy 46.355 240.03))
    (stroke (width 0) (type default))
  )
  (wire (pts (xy 59.69 142.875) (xy 59.69 140.97))
    (stroke (width 0) (type default))
  )
  (wire (pts (xy 34.925 140.97) (xy 31.115 140.97))
    (stroke (width 0) (type default))
  )
  (wire (pts (xy 156.21 199.39) (xy 153.67 199.39))
    (stroke (width 0) (type default))
  )
  (wire (pts (xy 67.945 32.385) (xy 67.945 34.925))
    (stroke (width 0) (type default))
  )
  (wire (pts (xy 99.06 149.225) (xy 107.315 149.225))
    (stroke (width 0) (type default))
  )
  (wire (pts (xy 176.53 93.98) (xy 180.34 93.98))
    (stroke (width 0) (type default))
  )
  (wire (pts (xy 84.455 41.275) (xy 76.2 41.275))
    (stroke (width 0) (type default))
  )
  (wire (pts (xy 188.595 64.77) (xy 189.865 64.77))
    (stroke (width 0) (type default))
  )
  (wire (pts (xy 236.22 85.09) (xy 236.22 83.82))
    (stroke (width 0) (type default))
  )
  (wire (pts (xy 55.88 242.57) (xy 46.355 242.57))
    (stroke (width 0) (type default))
  )
  (wire (pts (xy 363.22 113.03) (xy 378.46 113.03))
    (stroke (width 0) (type default))
  )
  (wire (pts (xy 334.645 74.93) (xy 332.74 74.93))
    (stroke (width 0) (type default))
  )
  (wire (pts (xy 369.57 237.49) (xy 370.84 237.49))
    (stroke (width 0) (type default))
  )
  (wire (pts (xy 318.135 199.39) (xy 318.135 200.66))
    (stroke (width 0) (type default))
  )
  (wire (pts (xy 167.005 93.98) (xy 171.45 93.98))
    (stroke (width 0) (type default))
  )
  (wire (pts (xy 317.5 33.02) (xy 321.945 33.02))
    (stroke (width 0) (type default))
  )
  (wire (pts (xy 172.085 154.94) (xy 180.34 154.94))
    (stroke (width 0) (type default))
  )
  (wire (pts (xy 59.69 149.225) (xy 59.69 147.955))
    (stroke (width 0) (type default))
  )
  (wire (pts (xy 289.56 144.78) (xy 292.735 144.78))
    (stroke (width 0) (type default))
  )
  (wire (pts (xy 205.105 213.995) (xy 205.105 229.87))
    (stroke (width 0) (type default))
  )
  (wire (pts (xy 321.945 30.48) (xy 334.645 30.48))
    (stroke (width 0) (type default))
  )
  (wire (pts (xy 172.085 149.86) (xy 180.34 149.86))
    (stroke (width 0) (type default))
  )
  (wire (pts (xy 111.76 95.885) (xy 111.76 97.155))
    (stroke (width 0) (type default))
  )
  (wire (pts (xy 188.595 59.69) (xy 189.865 59.69))
    (stroke (width 0) (type default))
  )
  (wire (pts (xy 212.725 234.95) (xy 212.725 232.41))
    (stroke (width 0) (type default))
  )
  (wire (pts (xy 189.865 44.45) (xy 187.96 44.45))
    (stroke (width 0) (type default))
  )
  (wire (pts (xy 188.595 71.12) (xy 189.865 71.12))
    (stroke (width 0) (type default))
  )
  (wire (pts (xy 236.22 90.17) (xy 236.22 91.44))
    (stroke (width 0) (type default))
  )
  (wire (pts (xy 240.03 147.32) (xy 231.14 147.32))
    (stroke (width 0) (type default))
  )
  (wire (pts (xy 342.9 166.37) (xy 349.885 166.37))
    (stroke (width 0) (type default))
  )
  (wire (pts (xy 196.85 147.32) (xy 196.85 149.86))
    (stroke (width 0) (type default))
  )
  (wire (pts (xy 103.505 88.9) (xy 99.06 88.9))
    (stroke (width 0) (type default))
  )
  (wire (pts (xy 337.185 122.555) (xy 358.14 122.555))
    (stroke (width 0) (type default))
  )
  (wire (pts (xy 323.85 60.96) (xy 334.645 60.96))
    (stroke (width 0) (type default))
  )
  (wire (pts (xy 240.03 134.62) (xy 231.14 134.62))
    (stroke (width 0) (type default))
  )
  (wire (pts (xy 36.83 242.57) (xy 36.83 240.665))
    (stroke (width 0) (type default))
  )
  (wire (pts (xy 281.305 207.01) (xy 281.305 214.63))
    (stroke (width 0) (type default))
  )
  (wire (pts (xy 43.18 149.225) (xy 51.435 149.225))
    (stroke (width 0) (type default))
  )
  (wire (pts (xy 180.34 109.22) (xy 180.34 111.125))
    (stroke (width 0) (type default))
  )
  (wire (pts (xy 92.71 41.275) (xy 84.455 41.275))
    (stroke (width 0) (type default))
  )
  (wire (pts (xy 212.725 237.49) (xy 220.345 237.49))
    (stroke (width 0) (type default))
  )
  (wire (pts (xy 185.42 147.32) (xy 196.85 147.32))
    (stroke (width 0) (type default))
  )
  (wire (pts (xy 365.125 165.1) (xy 365.125 166.37))
    (stroke (width 0) (type default))
  )
  (wire (pts (xy 361.315 63.5) (xy 377.19 63.5))
    (stroke (width 0) (type default))
  )
  (wire (pts (xy 381.635 211.455) (xy 381.635 214.63))
    (stroke (width 0) (type default))
  )
  (wire (pts (xy 111.76 88.9) (xy 103.505 88.9))
    (stroke (width 0) (type default))
  )
  (wire (pts (xy 381.635 196.215) (xy 379.095 196.215))
    (stroke (width 0) (type default))
  )
  (wire (pts (xy 33.02 242.57) (xy 33.02 244.475))
    (stroke (width 0) (type default))
  )
  (wire (pts (xy 34.925 149.225) (xy 34.925 147.955))
    (stroke (width 0) (type default))
  )
  (wire (pts (xy 185.42 160.02) (xy 196.85 160.02))
    (stroke (width 0) (type default))
  )
  (wire (pts (xy 357.505 165.1) (xy 357.505 166.37))
    (stroke (width 0) (type default))
  )
  (wire (pts (xy 220.345 234.95) (xy 212.725 234.95))
    (stroke (width 0) (type default))
  )
  (wire (pts (xy 180.34 139.7) (xy 172.085 139.7))
    (stroke (width 0) (type default))
  )
  (wire (pts (xy 342.9 157.48) (xy 349.885 157.48))
    (stroke (width 0) (type default))
  )
  (wire (pts (xy 317.5 122.555) (xy 332.105 122.555))
    (stroke (width 0) (type default))
  )
  (wire (pts (xy 43.18 140.97) (xy 34.925 140.97))
    (stroke (width 0) (type default))
  )
  (wire (pts (xy 361.315 69.85) (xy 377.19 69.85))
    (stroke (width 0) (type default))
  )
  (wire (pts (xy 67.945 41.275) (xy 59.69 41.275))
    (stroke (width 0) (type default))
  )
  (wire (pts (xy 260.985 209.55) (xy 266.065 209.55))
    (stroke (width 0) (type default))
  )
  (wire (pts (xy 364.49 46.99) (xy 361.315 46.99))
    (stroke (width 0) (type default))
  )
  (wire (pts (xy 342.9 157.48) (xy 342.9 160.02))
    (stroke (width 0) (type default))
  )
  (wire (pts (xy 180.34 93.98) (xy 180.34 102.87))
    (stroke (width 0) (type default))
  )
  (wire (pts (xy 241.3 34.29) (xy 234.315 34.29))
    (stroke (width 0) (type default))
  )
  (wire (pts (xy 115.57 147.955) (xy 115.57 149.225))
    (stroke (width 0) (type default))
  )
  (wire (pts (xy 173.99 219.71) (xy 176.53 219.71))
    (stroke (width 0) (type default))
  )
  (wire (pts (xy 320.04 157.48) (xy 327.66 157.48))
    (stroke (width 0) (type default))
  )
  (wire (pts (xy 33.02 229.87) (xy 33.02 235.585))
    (stroke (width 0) (type default))
  )
  (wire (pts (xy 255.905 139.7) (xy 255.905 142.24))
    (stroke (width 0) (type default))
  )
  (wire (pts (xy 29.845 96.52) (xy 29.845 98.425))
    (stroke (width 0) (type default))
  )
  (wire (pts (xy 231.14 149.86) (xy 240.03 149.86))
    (stroke (width 0) (type default))
  )
  (wire (pts (xy 29.845 98.425) (xy 29.845 100.33))
    (stroke (width 0) (type default))
  )
  (wire (pts (xy 397.51 199.39) (xy 400.05 199.39))
    (stroke (width 0) (type default))
  )
  (wire (pts (xy 320.04 157.48) (xy 320.04 160.02))
    (stroke (width 0) (type default))
  )
  (wire (pts (xy 188.595 54.61) (xy 189.865 54.61))
    (stroke (width 0) (type default))
  )
  (wire (pts (xy 167.005 91.44) (xy 189.865 91.44))
    (stroke (width 0) (type default))
  )
  (wire (pts (xy 317.5 125.095) (xy 332.105 125.095))
    (stroke (width 0) (type default))
  )
  (wire (pts (xy 227.965 229.87) (xy 238.125 229.87))
    (stroke (width 0) (type default))
  )
  (wire (pts (xy 240.03 152.4) (xy 231.14 152.4))
    (stroke (width 0) (type default))
  )
  (wire (pts (xy 200.025 199.39) (xy 200.025 207.645))
    (stroke (width 0) (type default))
  )
  (wire (pts (xy 337.185 125.095) (xy 358.14 125.095))
    (stroke (width 0) (type default))
  )
  (wire (pts (xy 92.71 32.385) (xy 100.965 32.385))
    (stroke (width 0) (type default))
  )
  (wire (pts (xy 238.125 227.33) (xy 239.395 227.33))
    (stroke (width 0) (type default))
  )
  (wire (pts (xy 318.135 205.74) (xy 318.135 206.375))
    (stroke (width 0) (type default))
  )
  (wire (pts (xy 260.985 212.09) (xy 273.685 212.09))
    (stroke (width 0) (type default))
  )
  (wire (pts (xy 225.425 226.695) (xy 225.425 229.87))
    (stroke (width 0) (type default))
  )
  (wire (pts (xy 76.2 32.385) (xy 84.455 32.385))
    (stroke (width 0) (type default))
  )
  (wire (pts (xy 132.08 88.9) (xy 120.015 88.9))
    (stroke (width 0) (type default))
  )
  (wire (pts (xy 234.315 93.98) (xy 236.22 93.98))
    (stroke (width 0) (type default))
  )
  (wire (pts (xy 43.18 40.005) (xy 43.18 41.275))
    (stroke (width 0) (type default))
  )
  (wire (pts (xy 188.595 48.26) (xy 189.865 48.26))
    (stroke (width 0) (type default))
  )
  (wire (pts (xy 54.61 88.9) (xy 46.355 88.9))
    (stroke (width 0) (type default))
  )
  (polyline (pts (xy 140.97 282.575) (xy 140.335 175.26))
    (stroke (width 0) (type default))
  )

  (wire (pts (xy 236.22 83.82) (xy 234.315 83.82))
    (stroke (width 0) (type default))
  )
  (wire (pts (xy 192.405 229.87) (xy 200.025 229.87))
    (stroke (width 0) (type default))
  )
  (wire (pts (xy 363.22 110.49) (xy 378.46 110.49))
    (stroke (width 0) (type default))
  )
  (wire (pts (xy 212.725 237.49) (xy 212.725 234.95))
    (stroke (width 0) (type default))
  )
  (wire (pts (xy 43.18 209.55) (xy 55.88 209.55))
    (stroke (width 0) (type default))
  )
  (wire (pts (xy 62.865 88.9) (xy 62.865 91.44))
    (stroke (width 0) (type default))
  )
  (wire (pts (xy 196.85 144.78) (xy 196.85 147.32))
    (stroke (width 0) (type default))
  )
  (wire (pts (xy 346.71 237.49) (xy 344.17 237.49))
    (stroke (width 0) (type default))
  )
  (wire (pts (xy 180.34 102.87) (xy 180.34 104.14))
    (stroke (width 0) (type default))
  )
  (wire (pts (xy 115.57 140.335) (xy 115.57 142.875))
    (stroke (width 0) (type default))
  )
  (wire (pts (xy 107.315 140.335) (xy 107.315 142.875))
    (stroke (width 0) (type default))
  )
  (wire (pts (xy 153.67 229.87) (xy 187.325 229.87))
    (stroke (width 0) (type default))
  )
  (wire (pts (xy 167.005 102.87) (xy 167.005 93.98))
    (stroke (width 0) (type default))
  )
  (wire (pts (xy 349.885 157.48) (xy 349.885 160.02))
    (stroke (width 0) (type default))
  )
  (wire (pts (xy 220.345 232.41) (xy 212.725 232.41))
    (stroke (width 0) (type default))
  )
  (wire (pts (xy 43.18 217.17) (xy 55.88 217.17))
    (stroke (width 0) (type default))
  )
  (wire (pts (xy 339.09 237.49) (xy 334.01 237.49))
    (stroke (width 0) (type default))
  )
  (wire (pts (xy 260.985 229.87) (xy 265.43 229.87))
    (stroke (width 0) (type default))
  )
  (wire (pts (xy 272.415 234.95) (xy 272.415 236.855))
    (stroke (width 0) (type default))
  )
  (wire (pts (xy 317.5 144.78) (xy 332.105 144.78))
    (stroke (width 0) (type default))
  )
  (wire (pts (xy 245.11 147.32) (xy 255.905 147.32))
    (stroke (width 0) (type default))
  )
  (wire (pts (xy 236.22 91.44) (xy 234.315 91.44))
    (stroke (width 0) (type default))
  )
  (wire (pts (xy 234.315 199.39) (xy 238.125 199.39))
    (stroke (width 0) (type default))
  )
  (wire (pts (xy 364.49 34.29) (xy 361.315 34.29))
    (stroke (width 0) (type default))
  )
  (wire (pts (xy 84.455 32.385) (xy 92.71 32.385))
    (stroke (width 0) (type default))
  )
  (wire (pts (xy 54.61 98.425) (xy 46.355 98.425))
    (stroke (width 0) (type default))
  )
  (wire (pts (xy 342.265 214.63) (xy 342.265 217.17))
    (stroke (width 0) (type default))
  )
  (wire (pts (xy 361.315 60.96) (xy 377.19 60.96))
    (stroke (width 0) (type default))
  )
  (wire (pts (xy 255.905 149.86) (xy 255.905 152.4))
    (stroke (width 0) (type default))
  )
  (wire (pts (xy 103.505 90.805) (xy 103.505 88.9))
    (stroke (width 0) (type default))
  )
  (wire (pts (xy 43.18 149.225) (xy 34.925 149.225))
    (stroke (width 0) (type default))
  )
  (wire (pts (xy 365.125 157.48) (xy 372.11 157.48))
    (stroke (width 0) (type default))
  )
  (wire (pts (xy 77.47 232.41) (xy 96.52 232.41))
    (stroke (width 0) (type default))
  )
  (wire (pts (xy 67.945 32.385) (xy 76.2 32.385))
    (stroke (width 0) (type default))
  )
  (wire (pts (xy 189.865 83.82) (xy 188.595 83.82))
    (stroke (width 0) (type default))
  )
  (wire (pts (xy 59.69 32.385) (xy 59.69 34.925))
    (stroke (width 0) (type default))
  )
  (wire (pts (xy 272.415 241.935) (xy 272.415 243.84))
    (stroke (width 0) (type default))
  )
  (wire (pts (xy 317.5 147.32) (xy 332.105 147.32))
    (stroke (width 0) (type default))
  )
  (wire (pts (xy 107.315 149.225) (xy 115.57 149.225))
    (stroke (width 0) (type default))
  )
  (wire (pts (xy 381.635 199.39) (xy 381.635 196.215))
    (stroke (width 0) (type default))
  )
  (wire (pts (xy 43.18 219.71) (xy 55.88 219.71))
    (stroke (width 0) (type default))
  )
  (wire (pts (xy 46.355 88.9) (xy 38.1 88.9))
    (stroke (width 0) (type default))
  )
  (wire (pts (xy 363.855 199.39) (xy 376.555 199.39))
    (stroke (width 0) (type default))
  )
  (wire (pts (xy 185.42 134.62) (xy 196.85 134.62))
    (stroke (width 0) (type default))
  )
  (wire (pts (xy 51.435 149.225) (xy 59.69 149.225))
    (stroke (width 0) (type default))
  )
  (wire (pts (xy 332.74 92.71) (xy 332.74 94.615))
    (stroke (width 0) (type default))
  )
  (wire (pts (xy 289.56 147.32) (xy 292.735 147.32))
    (stroke (width 0) (type default))
  )
  (wire (pts (xy 238.125 209.55) (xy 239.395 209.55))
    (stroke (width 0) (type default))
  )
  (wire (pts (xy 251.46 54.61) (xy 234.315 54.61))
    (stroke (width 0) (type default))
  )
  (wire (pts (xy 55.88 237.49) (xy 46.355 237.49))
    (stroke (width 0) (type default))
  )
  (wire (pts (xy 90.805 219.075) (xy 90.805 221.615))
    (stroke (width 0) (type default))
  )
  (wire (pts (xy 381.635 199.39) (xy 381.635 206.375))
    (stroke (width 0) (type default))
  )
  (wire (pts (xy 281.305 199.39) (xy 295.275 199.39))
    (stroke (width 0) (type default))
  )
  (wire (pts (xy 43.18 224.79) (xy 55.88 224.79))
    (stroke (width 0) (type default))
  )
  (wire (pts (xy 376.555 214.63) (xy 381.635 214.63))
    (stroke (width 0) (type default))
  )
  (wire (pts (xy 100.965 32.385) (xy 109.22 32.385))
    (stroke (width 0) (type default))
  )
  (wire (pts (xy 323.85 50.8) (xy 334.645 50.8))
    (stroke (width 0) (type default))
  )
  (wire (pts (xy 59.69 32.385) (xy 51.435 32.385))
    (stroke (width 0) (type default))
  )
  (wire (pts (xy 143.51 194.31) (xy 156.21 194.31))
    (stroke (width 0) (type default))
  )
  (wire (pts (xy 321.945 33.02) (xy 321.945 30.48))
    (stroke (width 0) (type default))
  )
  (wire (pts (xy 245.11 144.78) (xy 255.905 144.78))
    (stroke (width 0) (type default))
  )
  (wire (pts (xy 46.355 98.425) (xy 38.1 98.425))
    (stroke (width 0) (type default))
  )
  (wire (pts (xy 364.49 40.64) (xy 361.315 40.64))
    (stroke (width 0) (type default))
  )
  (wire (pts (xy 176.53 199.39) (xy 186.69 199.39))
    (stroke (width 0) (type default))
  )
  (wire (pts (xy 180.34 102.87) (xy 177.8 102.87))
    (stroke (width 0) (type default))
  )
  (wire (pts (xy 327.66 166.37) (xy 335.28 166.37))
    (stroke (width 0) (type default))
  )
  (wire (pts (xy 370.84 237.49) (xy 370.84 238.76))
    (stroke (width 0) (type default))
  )
  (wire (pts (xy 245.11 149.86) (xy 255.905 149.86))
    (stroke (width 0) (type default))
  )
  (wire (pts (xy 196.85 149.86) (xy 196.85 152.4))
    (stroke (width 0) (type default))
  )
  (wire (pts (xy 234.315 199.39) (xy 234.315 202.565))
    (stroke (width 0) (type default))
  )
  (wire (pts (xy 238.125 224.79) (xy 238.125 227.33))
    (stroke (width 0) (type default))
  )
  (wire (pts (xy 323.85 38.1) (xy 334.645 38.1))
    (stroke (width 0) (type default))
  )
  (wire (pts (xy 78.74 242.57) (xy 78.74 244.475))
    (stroke (width 0) (type default))
  )
  (wire (pts (xy 180.34 134.62) (xy 172.085 134.62))
    (stroke (width 0) (type default))
  )
  (wire (pts (xy 332.74 74.93) (xy 332.74 90.17))
    (stroke (width 0) (type default))
  )
  (wire (pts (xy 99.06 140.335) (xy 99.06 142.875))
    (stroke (width 0) (type default))
  )
  (wire (pts (xy 78.74 242.57) (xy 77.47 242.57))
    (stroke (width 0) (type default))
  )
  (wire (pts (xy 26.035 140.97) (xy 23.495 140.97))
    (stroke (width 0) (type default))
  )
  (wire (pts (xy 323.85 43.18) (xy 334.645 43.18))
    (stroke (width 0) (type default))
  )
  (wire (pts (xy 62.865 96.52) (xy 62.865 98.425))
    (stroke (width 0) (type default))
  )
  (wire (pts (xy 59.69 140.97) (xy 51.435 140.97))
    (stroke (width 0) (type default))
  )
  (wire (pts (xy 361.315 76.2) (xy 377.19 76.2))
    (stroke (width 0) (type default))
  )
  (wire (pts (xy 302.26 199.39) (xy 309.245 199.39))
    (stroke (width 0) (type default))
  )
  (wire (pts (xy 36.83 232.41) (xy 36.83 235.585))
    (stroke (width 0) (type default))
  )
  (wire (pts (xy 109.22 41.275) (xy 100.965 41.275))
    (stroke (width 0) (type default))
  )
  (wire (pts (xy 317.5 30.48) (xy 321.945 30.48))
    (stroke (width 0) (type default))
  )
  (wire (pts (xy 260.985 214.63) (xy 281.305 214.63))
    (stroke (width 0) (type default))
  )
  (wire (pts (xy 335.28 157.48) (xy 335.28 160.02))
    (stroke (width 0) (type default))
  )
  (wire (pts (xy 332.74 90.17) (xy 334.645 90.17))
    (stroke (width 0) (type default))
  )
  (wire (pts (xy 120.015 88.9) (xy 111.76 88.9))
    (stroke (width 0) (type default))
  )
  (wire (pts (xy 189.865 62.23) (xy 188.595 62.23))
    (stroke (width 0) (type default))
  )
  (wire (pts (xy 225.425 217.17) (xy 225.425 221.615))
    (stroke (width 0) (type default))
  )
  (wire (pts (xy 176.53 199.39) (xy 176.53 219.71))
    (stroke (width 0) (type default))
  )
  (wire (pts (xy 255.905 154.94) (xy 255.905 156.21))
    (stroke (width 0) (type default))
  )
  (wire (pts (xy 51.435 32.385) (xy 51.435 34.925))
    (stroke (width 0) (type default))
  )
  (wire (pts (xy 43.18 41.275) (xy 43.18 42.545))
    (stroke (width 0) (type default))
  )
  (wire (pts (xy 196.85 137.16) (xy 196.85 139.7))
    (stroke (width 0) (type default))
  )
  (wire (pts (xy 361.315 92.71) (xy 377.19 92.71))
    (stroke (width 0) (type default))
  )
  (wire (pts (xy 90.805 229.87) (xy 90.805 226.695))
    (stroke (width 0) (type default))
  )
  (wire (pts (xy 67.945 32.385) (xy 59.69 32.385))
    (stroke (width 0) (type default))
  )
  (wire (pts (xy 196.85 152.4) (xy 196.85 154.94))
    (stroke (width 0) (type default))
  )
  (wire (pts (xy 365.125 157.48) (xy 365.125 160.02))
    (stroke (width 0) (type default))
  )
  (wire (pts (xy 260.985 242.57) (xy 262.255 242.57))
    (stroke (width 0) (type default))
  )
  (wire (pts (xy 245.11 154.94) (xy 255.905 154.94))
    (stroke (width 0) (type default))
  )
  (wire (pts (xy 343.535 207.01) (xy 330.835 207.01))
    (stroke (width 0) (type default))
  )
  (wire (pts (xy 251.46 48.26) (xy 234.315 48.26))
    (stroke (width 0) (type default))
  )
  (wire (pts (xy 255.905 137.16) (xy 255.905 139.7))
    (stroke (width 0) (type default))
  )
  (wire (pts (xy 54.61 88.9) (xy 54.61 91.44))
    (stroke (width 0) (type default))
  )
  (wire (pts (xy 309.245 199.39) (xy 318.135 199.39))
    (stroke (width 0) (type default))
  )
  (wire (pts (xy 337.185 110.49) (xy 358.14 110.49))
    (stroke (width 0) (type default))
  )
  (wire (pts (xy 38.1 96.52) (xy 38.1 98.425))
    (stroke (width 0) (type default))
  )
  (wire (pts (xy 359.41 237.49) (xy 364.49 237.49))
    (stroke (width 0) (type default))
  )
  (wire (pts (xy 100.965 40.005) (xy 100.965 41.275))
    (stroke (width 0) (type default))
  )
  (wire (pts (xy 189.865 93.98) (xy 180.34 93.98))
    (stroke (width 0) (type default))
  )
  (wire (pts (xy 251.46 57.15) (xy 234.315 57.15))
    (stroke (width 0) (type default))
  )
  (wire (pts (xy 55.88 229.87) (xy 33.02 229.87))
    (stroke (width 0) (type default))
  )
  (wire (pts (xy 196.85 139.7) (xy 196.85 142.24))
    (stroke (width 0) (type default))
  )
  (wire (pts (xy 328.295 77.47) (xy 334.645 77.47))
    (stroke (width 0) (type default))
  )
  (wire (pts (xy 376.555 199.39) (xy 376.555 206.375))
    (stroke (width 0) (type default))
  )
  (wire (pts (xy 90.805 219.075) (xy 93.98 219.075))
    (stroke (width 0) (type default))
  )
  (wire (pts (xy 363.22 125.095) (xy 378.46 125.095))
    (stroke (width 0) (type default))
  )
  (wire (pts (xy 234.315 76.2) (xy 235.585 76.2))
    (stroke (width 0) (type default))
  )
  (wire (pts (xy 67.945 40.005) (xy 67.945 41.275))
    (stroke (width 0) (type default))
  )
  (wire (pts (xy 386.715 199.39) (xy 386.715 206.375))
    (stroke (width 0) (type default))
  )

  (text "PoE" (at 146.05 183.515 0)
    (effects (font (size 2.9972 2.9972) (thickness 0.5994) bold) (justify left bottom))
  )
  (text "DVDDL decoupling" (at 56.515 23.495 0)
    (effects (font (size 2.9972 2.9972) (thickness 0.5994) bold) (justify left bottom))
  )
  (text "AVDDL decoupling" (at 16.51 127.635 0)
    (effects (font (size 2.9972 2.9972) (thickness 0.5994) bold) (justify left bottom))
  )
  (text "Pull down resistors" (at 215.9 127.635 0)
    (effects (font (size 2.9972 2.9972) (thickness 0.5994) bold) (justify left bottom))
  )
  (text "DVDDH decoupling" (at 19.05 75.565 0)
    (effects (font (size 2.9972 2.9972) (thickness 0.5994) bold) (justify left bottom))
  )
  (text "Use when ETH on FMC is needed" (at 281.94 23.495 0)
    (effects (font (size 1.27 1.27)) (justify left bottom))
  )
  (text "Do not use mux with PoE" (at 335.915 97.79 0)
    (effects (font (size 1.27 1.27)) (justify left bottom))
  )
  (text "RJ45 Connector" (at 85.725 182.245 0)
    (effects (font (size 2.9972 2.9972) (thickness 0.5994) bold) (justify right bottom))
  )
  (text "AVDDH decoupling" (at 83.185 127.635 0)
    (effects (font (size 2.9972 2.9972) (thickness 0.5994) bold) (justify left bottom))
  )
  (text "PHY" (at 207.01 22.225 0)
    (effects (font (size 2.9972 2.9972) (thickness 0.5994) bold) (justify left bottom))
  )
  (text "Pull up resistors" (at 161.29 128.27 0)
    (effects (font (size 2.9972 2.9972) (thickness 0.5994) bold) (justify left bottom))
  )
  (text "ETH mux" (at 281.305 20.955 0)
    (effects (font (size 2.9972 2.9972) (thickness 0.5994) bold) (justify left bottom))
  )
  (text "AVDDL_PLL decoupling" (at 81.28 76.2 0)
    (effects (font (size 2.9972 2.9972) (thickness 0.5994) bold) (justify left bottom))
  )
  (text "Stubless mux passthrough" (at 315.595 105.41 0)
    (effects (font (size 1.27 1.27)) (justify left bottom))
  )

  (label "INT_ETH4_N" (at 377.19 82.55 180) (fields_autoplaced)
    (effects (font (size 1.27 1.27)) (justify right bottom))
  )
  (label "ETH3_P" (at 251.46 60.96 180) (fields_autoplaced)
    (effects (font (size 1.27 1.27)) (justify right bottom))
  )
  (label "INT_ETH4_P" (at 43.18 222.25 0) (fields_autoplaced)
    (effects (font (size 1.27 1.27)) (justify left bottom))
  )
  (label "INT_ETH4_P" (at 377.19 80.01 180) (fields_autoplaced)
    (effects (font (size 1.27 1.27)) (justify right bottom))
  )
  (label "ETH2_P" (at 323.85 43.18 0) (fields_autoplaced)
    (effects (font (size 1.27 1.27)) (justify left bottom))
  )
  (label "PAIR_12" (at 143.51 204.47 0) (fields_autoplaced)
    (effects (font (size 1.27 1.27)) (justify left bottom))
  )
  (label "INT_ETH2_P" (at 43.18 212.09 0) (fields_autoplaced)
    (effects (font (size 1.27 1.27)) (justify left bottom))
  )
  (label "TPH" (at 261.62 209.55 0) (fields_autoplaced)
    (effects (font (size 1.27 1.27)) (justify left bottom))
  )
  (label "TPL" (at 261.62 212.09 0) (fields_autoplaced)
    (effects (font (size 1.27 1.27)) (justify left bottom))
  )
  (label "ETH1_P" (at 317.5 110.49 0) (fields_autoplaced)
    (effects (font (size 1.27 1.27)) (justify left bottom))
  )
  (label "ETH3_P" (at 323.85 50.8 0) (fields_autoplaced)
    (effects (font (size 1.27 1.27)) (justify left bottom))
  )
  (label "INT_ETH3_N" (at 43.18 219.71 0) (fields_autoplaced)
    (effects (font (size 1.27 1.27)) (justify left bottom))
  )
  (label "ETH4_BP_N" (at 351.155 147.32 180) (fields_autoplaced)
    (effects (font (size 1.27 1.27)) (justify right bottom))
  )
  (label "POE_ACTIVE" (at 283.21 229.87 180) (fields_autoplaced)
    (effects (font (size 1.27 1.27)) (justify right bottom))
  )
  (label "INT_LED_LINK" (at 313.055 144.78 180) (fields_autoplaced)
    (effects (font (size 1.27 1.27)) (justify right bottom))
  )
  (label "INT_ETH3_P" (at 378.46 133.985 180) (fields_autoplaced)
    (effects (font (size 1.27 1.27)) (justify right bottom))
  )
  (label "AVDDH" (at 123.825 140.335 180) (fields_autoplaced)
    (effects (font (size 1.27 1.27)) (justify right bottom))
  )
  (label "ETH3_N" (at 251.46 63.5 180) (fields_autoplaced)
    (effects (font (size 1.27 1.27)) (justify right bottom))
  )
  (label "ETH3_BP_N" (at 351.155 136.525 180) (fields_autoplaced)
    (effects (font (size 1.27 1.27)) (justify right bottom))
  )
  (label "ETH3_N" (at 317.5 136.525 0) (fields_autoplaced)
    (effects (font (size 1.27 1.27)) (justify left bottom))
  )
  (label "ETH3_N" (at 323.85 53.34 0) (fields_autoplaced)
    (effects (font (size 1.27 1.27)) (justify left bottom))
  )
  (label "ETH2_N" (at 323.85 45.72 0) (fields_autoplaced)
    (effects (font (size 1.27 1.27)) (justify left bottom))
  )
  (label "INT_ETH3_N" (at 377.19 76.2 180) (fields_autoplaced)
    (effects (font (size 1.27 1.27)) (justify right bottom))
  )
  (label "INT_ETH1_P" (at 378.46 110.49 180) (fields_autoplaced)
    (effects (font (size 1.27 1.27)) (justify right bottom))
  )
  (label "ETH2_N" (at 317.5 125.095 0) (fields_autoplaced)
    (effects (font (size 1.27 1.27)) (justify left bottom))
  )
  (label "ETH4_N" (at 251.46 69.85 180) (fields_autoplaced)
    (effects (font (size 1.27 1.27)) (justify right bottom))
  )
  (label "INT_ETH1_P" (at 43.18 207.01 0) (fields_autoplaced)
    (effects (font (size 1.27 1.27)) (justify left bottom))
  )
  (label "ETH2_BP_N" (at 351.155 125.095 180) (fields_autoplaced)
    (effects (font (size 1.27 1.27)) (justify right bottom))
  )
  (label "ETH1_P" (at 251.46 48.26 180) (fields_autoplaced)
    (effects (font (size 1.27 1.27)) (justify right bottom))
  )
  (label "ETH1_BP_P" (at 351.155 110.49 180) (fields_autoplaced)
    (effects (font (size 1.27 1.27)) (justify right bottom))
  )
  (label "ETH2_P" (at 251.46 54.61 180) (fields_autoplaced)
    (effects (font (size 1.27 1.27)) (justify right bottom))
  )
  (label "INT_ETH3_P" (at 43.18 217.17 0) (fields_autoplaced)
    (effects (font (size 1.27 1.27)) (justify left bottom))
  )
  (label "INT_ETH3_P" (at 377.19 73.66 180) (fields_autoplaced)
    (effects (font (size 1.27 1.27)) (justify right bottom))
  )
  (label "AVDDL_PLL" (at 132.08 88.9 180) (fields_autoplaced)
    (effects (font (size 1.27 1.27)) (justify right bottom))
  )
  (label "POE_ACTIVE" (at 330.835 207.01 0) (fields_autoplaced)
    (effects (font (size 1.27 1.27)) (justify left bottom))
  )
  (label "VSS" (at 207.01 229.87 0) (fields_autoplaced)
    (effects (font (size 1.27 1.27)) (justify left bottom))
  )
  (label "ETH4_BP_P" (at 351.155 144.78 180) (fields_autoplaced)
    (effects (font (size 1.27 1.27)) (justify right bottom))
  )
  (label "PAIR_12" (at 46.355 234.95 0) (fields_autoplaced)
    (effects (font (size 1.27 1.27)) (justify left bottom))
  )
  (label "ETH1_P" (at 323.85 35.56 0) (fields_autoplaced)
    (effects (font (size 1.27 1.27)) (justify left bottom))
  )
  (label "INT_ETH2_P" (at 377.19 67.31 180) (fields_autoplaced)
    (effects (font (size 1.27 1.27)) (justify right bottom))
  )
  (label "POE_ACTIVE" (at 372.11 233.68 180) (fields_autoplaced)
    (effects (font (size 1.27 1.27)) (justify right bottom))
  )
  (label "PAIR_78" (at 46.355 240.03 0) (fields_autoplaced)
    (effects (font (size 1.27 1.27)) (justify left bottom))
  )
  (label "INT_ETH1_N" (at 378.46 113.03 180) (fields_autoplaced)
    (effects (font (size 1.27 1.27)) (justify right bottom))
  )
  (label "ETH3_P" (at 317.5 133.985 0) (fields_autoplaced)
    (effects (font (size 1.27 1.27)) (justify left bottom))
  )
  (label "INT_ETH1_N" (at 43.18 209.55 0) (fields_autoplaced)
    (effects (font (size 1.27 1.27)) (justify left bottom))
  )
  (label "CLSA" (at 227.965 217.17 0) (fields_autoplaced)
    (effects (font (size 1.27 1.27)) (justify left bottom))
  )
  (label "ETH2_N" (at 251.46 57.15 180) (fields_autoplaced)
    (effects (font (size 1.27 1.27)) (justify right bottom))
  )
  (label "ETH1_N" (at 251.46 50.8 180) (fields_autoplaced)
    (effects (font (size 1.27 1.27)) (justify right bottom))
  )
  (label "CLSB" (at 233.045 219.71 180) (fields_autoplaced)
    (effects (font (size 1.27 1.27)) (justify right bottom))
  )
  (label "INT_ETH4_P" (at 378.46 144.78 180) (fields_autoplaced)
    (effects (font (size 1.27 1.27)) (justify right bottom))
  )
  (label "AVDDH" (at 177.8 38.1 0) (fields_autoplaced)
    (effects (font (size 1.27 1.27)) (justify left bottom))
  )
  (label "INT_ETH4_N" (at 43.18 224.79 0) (fields_autoplaced)
    (effects (font (size 1.27 1.27)) (justify left bottom))
  )
  (label "PAIR_78" (at 143.51 214.63 0) (fields_autoplaced)
    (effects (font (size 1.27 1.27)) (justify left bottom))
  )
  (label "VSS_RAW" (at 176.53 229.87 0) (fields_autoplaced)
    (effects (font (size 1.27 1.27)) (justify left bottom))
  )
  (label "VDD_RAW" (at 176.53 199.39 0) (fields_autoplaced)
    (effects (font (size 1.27 1.27)) (justify left bottom))
  )
  (label "PG" (at 264.16 229.87 180) (fields_autoplaced)
    (effects (font (size 1.27 1.27)) (justify right bottom))
  )
  (label "PAIR_36" (at 143.51 194.31 0) (fields_autoplaced)
    (effects (font (size 1.27 1.27)) (justify left bottom))
  )
  (label "REF" (at 239.395 234.95 180) (fields_autoplaced)
    (effects (font (size 1.27 1.27)) (justify right bottom))
  )
  (label "INT_LED_LINK" (at 377.19 90.17 180) (fields_autoplaced)
    (effects (font (size 1.27 1.27)) (justify right bottom))
  )
  (label "ETH1_BP_N" (at 351.155 113.03 180) (fields_autoplaced)
    (effects (font (size 1.27 1.27)) (justify right bottom))
  )
  (label "INT_LED_SPD" (at 377.19 92.71 180) (fields_autoplaced)
    (effects (font (size 1.27 1.27)) (justify right bottom))
  )
  (label "ETH1_N" (at 317.5 113.03 0) (fields_autoplaced)
    (effects (font (size 1.27 1.27)) (justify left bottom))
  )
  (label "AVDDL" (at 251.46 38.1 180) (fields_autoplaced)
    (effects (font (size 1.27 1.27)) (justify right bottom))
  )
  (label "PAIR_910" (at 46.355 242.57 0) (fields_autoplaced)
    (effects (font (size 1.27 1.27)) (justify left bottom))
  )
  (label "PAIR_910" (at 143.51 224.79 0) (fields_autoplaced)
    (effects (font (size 1.27 1.27)) (justify left bottom))
  )
  (label "INT_ETH2_N" (at 43.18 214.63 0) (fields_autoplaced)
    (effects (font (size 1.27 1.27)) (justify left bottom))
  )
  (label "INT_ETH2_P" (at 378.46 122.555 180) (fields_autoplaced)
    (effects (font (size 1.27 1.27)) (justify right bottom))
  )
  (label "DEN" (at 238.76 212.09 180) (fields_autoplaced)
    (effects (font (size 1.27 1.27)) (justify right bottom))
  )
  (label "AVDDL_PLL" (at 251.46 40.64 180) (fields_autoplaced)
    (effects (font (size 1.27 1.27)) (justify right bottom))
  )
  (label "INT_ETH4_N" (at 378.46 147.32 180) (fields_autoplaced)
    (effects (font (size 1.27 1.27)) (justify right bottom))
  )
  (label "PAIR_36" (at 46.355 237.49 0) (fields_autoplaced)
    (effects (font (size 1.27 1.27)) (justify left bottom))
  )
  (label "ETH4_P" (at 317.5 144.78 0) (fields_autoplaced)
    (effects (font (size 1.27 1.27)) (justify left bottom))
  )
  (label "INT_ETH2_N" (at 377.19 69.85 180) (fields_autoplaced)
    (effects (font (size 1.27 1.27)) (justify right bottom))
  )
  (label "ETH2_P" (at 317.5 122.555 0) (fields_autoplaced)
    (effects (font (size 1.27 1.27)) (justify left bottom))
  )
  (label "ETH4_N" (at 323.85 60.96 0) (fields_autoplaced)
    (effects (font (size 1.27 1.27)) (justify left bottom))
  )
  (label "ETH4_N" (at 317.5 147.32 0) (fields_autoplaced)
    (effects (font (size 1.27 1.27)) (justify left bottom))
  )
  (label "ETH2_BP_P" (at 351.155 122.555 180) (fields_autoplaced)
    (effects (font (size 1.27 1.27)) (justify right bottom))
  )
  (label "INT_ETH1_P" (at 377.19 60.96 180) (fields_autoplaced)
    (effects (font (size 1.27 1.27)) (justify right bottom))
  )
  (label "INT_ETH1_N" (at 377.19 63.5 180) (fields_autoplaced)
    (effects (font (size 1.27 1.27)) (justify right bottom))
  )
  (label "ETH4_P" (at 251.46 67.31 180) (fields_autoplaced)
    (effects (font (size 1.27 1.27)) (justify right bottom))
  )
  (label "ETH4_P" (at 323.85 58.42 0) (fields_autoplaced)
    (effects (font (size 1.27 1.27)) (justify left bottom))
  )
  (label "INT_LED_SPD" (at 313.055 147.32 180) (fields_autoplaced)
    (effects (font (size 1.27 1.27)) (justify right bottom))
  )
  (label "VDD" (at 207.01 199.39 0) (fields_autoplaced)
    (effects (font (size 1.27 1.27)) (justify left bottom))
  )
  (label "MPS_DUTY" (at 239.395 237.49 180) (fields_autoplaced)
    (effects (font (size 1.27 1.27)) (justify right bottom))
  )
  (label "IRSHDL_EN" (at 272.415 234.95 180) (fields_autoplaced)
    (effects (font (size 1.27 1.27)) (justify right bottom))
  )
  (label "AVDDL" (at 67.945 140.97 180) (fields_autoplaced)
    (effects (font (size 1.27 1.27)) (justify right bottom))
  )
  (label "ETH1_N" (at 323.85 38.1 0) (fields_autoplaced)
    (effects (font (size 1.27 1.27)) (justify left bottom))
  )
  (label "AMPS_CTL" (at 239.395 232.41 180) (fields_autoplaced)
    (effects (font (size 1.27 1.27)) (justify right bottom))
  )
  (label "ETH3_BP_P" (at 351.155 133.985 180) (fields_autoplaced)
    (effects (font (size 1.27 1.27)) (justify right bottom))
  )
  (label "INT_ETH2_N" (at 378.46 125.095 180) (fields_autoplaced)
    (effects (font (size 1.27 1.27)) (justify right bottom))
  )
  (label "INT_ETH3_N" (at 378.46 136.525 180) (fields_autoplaced)
    (effects (font (size 1.27 1.27)) (justify right bottom))
  )

  (global_label "ETH_MDC" (shape input) (at 188.595 48.26 180) (fields_autoplaced)
    (effects (font (size 1.27 1.27)) (justify right))
    (property "Intersheetrefs" "${INTERSHEET_REFS}" (at 10.16 -27.305 0)
      (effects (font (size 1.27 1.27)) hide)
    )
  )
  (global_label "EXT_ETH3_N" (shape input) (at 364.49 40.64 0) (fields_autoplaced)
    (effects (font (size 1.27 1.27)) (justify left))
    (property "Intersheetrefs" "${INTERSHEET_REFS}" (at 378.0628 40.5606 0)
      (effects (font (size 1.27 1.27)) (justify left) hide)
    )
  )
  (global_label "INT_LED_LINK" (shape input) (at 96.52 232.41 0) (fields_autoplaced)
    (effects (font (size 1.27 1.27)) (justify left))
    (property "Intersheetrefs" "${INTERSHEET_REFS}" (at 111.3628 232.3306 0)
      (effects (font (size 1.27 1.27)) (justify left) hide)
    )
  )
  (global_label "ETH_RXD1" (shape input) (at 172.085 137.16 180) (fields_autoplaced)
    (effects (font (size 1.27 1.27)) (justify right))
    (property "Intersheetrefs" "${INTERSHEET_REFS}" (at -156.21 80.01 0)
      (effects (font (size 1.27 1.27)) (justify right) hide)
    )
  )
  (global_label "ETH_RX_CLK" (shape input) (at 231.14 147.32 180) (fields_autoplaced)
    (effects (font (size 1.27 1.27)) (justify right))
    (property "Intersheetrefs" "${INTERSHEET_REFS}" (at -97.155 21.59 0)
      (effects (font (size 1.27 1.27)) hide)
    )
  )
  (global_label "EXT_ETH4_N" (shape input) (at 364.49 46.99 0) (fields_autoplaced)
    (effects (font (size 1.27 1.27)) (justify left))
    (property "Intersheetrefs" "${INTERSHEET_REFS}" (at 378.0628 46.9106 0)
      (effects (font (size 1.27 1.27)) (justify left) hide)
    )
  )
  (global_label "LED_SPD" (shape input) (at 231.14 152.4 180) (fields_autoplaced)
    (effects (font (size 1.27 1.27)) (justify right))
    (property "Intersheetrefs" "${INTERSHEET_REFS}" (at -97.155 21.59 0)
      (effects (font (size 1.27 1.27)) hide)
    )
  )
  (global_label "ETH_RXD0" (shape input) (at 231.14 134.62 180) (fields_autoplaced)
    (effects (font (size 1.27 1.27)) (justify right))
    (property "Intersheetrefs" "${INTERSHEET_REFS}" (at -97.155 21.59 0)
      (effects (font (size 1.27 1.27)) hide)
    )
  )
  (global_label "3V3_SYS" (shape input) (at 186.69 34.29 180) (fields_autoplaced)
    (effects (font (size 1.27 1.27)) (justify right))
    (property "Intersheetrefs" "${INTERSHEET_REFS}" (at 127.635 -112.395 0)
      (effects (font (size 1.27 1.27)) hide)
    )
  )
  (global_label "ETH_RXD0" (shape input) (at 188.595 73.66 180) (fields_autoplaced)
    (effects (font (size 1.27 1.27)) (justify right))
    (property "Intersheetrefs" "${INTERSHEET_REFS}" (at 10.16 -29.845 0)
      (effects (font (size 1.27 1.27)) hide)
    )
  )
  (global_label "3V3_SYS" (shape input) (at 91.44 140.335 180) (fields_autoplaced)
    (effects (font (size 1.27 1.27)) (justify right))
    (property "Intersheetrefs" "${INTERSHEET_REFS}" (at 40.64 48.26 0)
      (effects (font (size 1.27 1.27)) hide)
    )
  )
  (global_label "EXT_ETH4_P" (shape input) (at 364.49 44.45 0) (fields_autoplaced)
    (effects (font (size 1.27 1.27)) (justify left))
    (property "Intersheetrefs" "${INTERSHEET_REFS}" (at 378.0023 44.3706 0)
      (effects (font (size 1.27 1.27)) (justify left) hide)
    )
  )
  (global_label "EXT_LED_LINK" (shape input) (at 364.49 53.34 0) (fields_autoplaced)
    (effects (font (size 1.27 1.27)) (justify left))
    (property "Intersheetrefs" "${INTERSHEET_REFS}" (at 379.7561 53.2606 0)
      (effects (font (size 1.27 1.27)) (justify left) hide)
    )
  )
  (global_label "ETH_TXD2" (shape input) (at 188.595 62.23 180) (fields_autoplaced)
    (effects (font (size 1.27 1.27)) (justify right))
    (property "Intersheetrefs" "${INTERSHEET_REFS}" (at 10.16 -28.575 0)
      (effects (font (size 1.27 1.27)) hide)
    )
  )
  (global_label "VIN_POE" (shape input) (at 379.095 196.215 180) (fields_autoplaced)
    (effects (font (size 1.27 1.27)) (justify right))
    (property "Intersheetrefs" "${INTERSHEET_REFS}" (at 369.0298 196.2944 0)
      (effects (font (size 1.27 1.27)) (justify right) hide)
    )
  )
  (global_label "ETH_TXD1" (shape input) (at 188.595 59.69 180) (fields_autoplaced)
    (effects (font (size 1.27 1.27)) (justify right))
    (property "Intersheetrefs" "${INTERSHEET_REFS}" (at 10.16 -28.575 0)
      (effects (font (size 1.27 1.27)) hide)
    )
  )
  (global_label "LED_LINK" (shape input) (at 289.56 144.78 180) (fields_autoplaced)
    (effects (font (size 1.27 1.27)) (justify right))
    (property "Intersheetrefs" "${INTERSHEET_REFS}" (at 111.125 266.065 0)
      (effects (font (size 1.27 1.27)) hide)
    )
  )
  (global_label "EXT_ETH2_P" (shape input) (at 364.49 31.75 0) (fields_autoplaced)
    (effects (font (size 1.27 1.27)) (justify left))
    (property "Intersheetrefs" "${INTERSHEET_REFS}" (at 378.0023 31.6706 0)
      (effects (font (size 1.27 1.27)) (justify left) hide)
    )
  )
  (global_label "ETH_RXD2" (shape input) (at 231.14 139.7 180) (fields_autoplaced)
    (effects (font (size 1.27 1.27)) (justify right))
    (property "Intersheetrefs" "${INTERSHEET_REFS}" (at -97.155 21.59 0)
      (effects (font (size 1.27 1.27)) hide)
    )
  )
  (global_label "ETH_RSTN" (shape input) (at 172.085 160.02 180) (fields_autoplaced)
    (effects (font (size 1.27 1.27)) (justify right))
    (property "Intersheetrefs" "${INTERSHEET_REFS}" (at -156.21 80.01 0)
      (effects (font (size 1.27 1.27)) (justify right) hide)
    )
  )
  (global_label "ETH_SEL" (shape input) (at 306.705 33.02 180) (fields_autoplaced)
    (effects (font (size 1.27 1.27)) (justify right))
    (property "Intersheetrefs" "${INTERSHEET_REFS}" (at 296.5794 32.9406 0)
      (effects (font (size 1.27 1.27)) (justify right) hide)
    )
  )
  (global_label "PRSNT_M2C" (shape input) (at 306.705 30.48 180) (fields_autoplaced)
    (effects (font (size 1.27 1.27)) (justify right))
    (property "Intersheetrefs" "${INTERSHEET_REFS}" (at 293.4346 30.4006 0)
      (effects (font (size 1.27 1.27)) (justify right) hide)
    )
  )
  (global_label "LED_SPD" (shape input) (at 328.295 80.01 180) (fields_autoplaced)
    (effects (font (size 1.27 1.27)) (justify right))
    (property "Intersheetrefs" "${INTERSHEET_REFS}" (at 149.86 198.755 0)
      (effects (font (size 1.27 1.27)) hide)
    )
  )
  (global_label "1V2_SYS" (shape input) (at 241.3 34.29 0) (fields_autoplaced)
    (effects (font (size 1.27 1.27)) (justify left))
    (property "Intersheetrefs" "${INTERSHEET_REFS}" (at 274.32 -10.16 0)
      (effects (font (size 1.27 1.27)) hide)
    )
  )
  (global_label "ETH_INT_N" (shape output) (at 187.96 44.45 180) (fields_autoplaced)
    (effects (font (size 1.27 1.27)) (justify right))
    (property "Intersheetrefs" "${INTERSHEET_REFS}" (at 10.16 -79.375 0)
      (effects (font (size 1.27 1.27)) hide)
    )
  )
  (global_label "LED_LINK" (shape input) (at 172.085 154.94 180) (fields_autoplaced)
    (effects (font (size 1.27 1.27)) (justify right))
    (property "Intersheetrefs" "${INTERSHEET_REFS}" (at -156.21 80.01 0)
      (effects (font (size 1.27 1.27)) (justify right) hide)
    )
  )
  (global_label "ETH_RXD2" (shape input) (at 188.595 78.74 180) (fields_autoplaced)
    (effects (font (size 1.27 1.27)) (justify right))
    (property "Intersheetrefs" "${INTERSHEET_REFS}" (at 10.16 -29.845 0)
      (effects (font (size 1.27 1.27)) hide)
    )
  )
  (global_label "ETH_REF_CLK" (shape input) (at 172.085 149.86 180) (fields_autoplaced)
    (effects (font (size 1.27 1.27)) (justify right))
    (property "Intersheetrefs" "${INTERSHEET_REFS}" (at -156.21 80.01 0)
      (effects (font (size 1.27 1.27)) (justify right) hide)
    )
  )
  (global_label "ETH_RXD2" (shape input) (at 172.085 139.7 180) (fields_autoplaced)
    (effects (font (size 1.27 1.27)) (justify right))
    (property "Intersheetrefs" "${INTERSHEET_REFS}" (at -156.21 80.01 0)
      (effects (font (size 1.27 1.27)) (justify right) hide)
    )
  )
  (global_label "ETH_RXD1" (shape input) (at 231.14 137.16 180) (fields_autoplaced)
    (effects (font (size 1.27 1.27)) (justify right))
    (property "Intersheetrefs" "${INTERSHEET_REFS}" (at -97.155 21.59 0)
      (effects (font (size 1.27 1.27)) hide)
    )
  )
  (global_label "LED_SPD" (shape input) (at 289.56 147.32 180) (fields_autoplaced)
    (effects (font (size 1.27 1.27)) (justify right))
    (property "Intersheetrefs" "${INTERSHEET_REFS}" (at 111.125 266.065 0)
      (effects (font (size 1.27 1.27)) hide)
    )
  )
  (global_label "EXT_ETH3_P" (shape input) (at 364.49 38.1 0) (fields_autoplaced)
    (effects (font (size 1.27 1.27)) (justify left))
    (property "Intersheetrefs" "${INTERSHEET_REFS}" (at 378.0023 38.0206 0)
      (effects (font (size 1.27 1.27)) (justify left) hide)
    )
  )
  (global_label "ETH_MDIO" (shape input) (at 188.595 50.8 180) (fields_autoplaced)
    (effects (font (size 1.27 1.27)) (justify right))
    (property "Intersheetrefs" "${INTERSHEET_REFS}" (at 10.16 -27.305 0)
      (effects (font (size 1.27 1.27)) hide)
    )
  )
  (global_label "ETH_TXD3" (shape input) (at 188.595 64.77 180) (fields_autoplaced)
    (effects (font (size 1.27 1.27)) (justify right))
    (property "Intersheetrefs" "${INTERSHEET_REFS}" (at 10.16 -28.575 0)
      (effects (font (size 1.27 1.27)) hide)
    )
  )
  (global_label "VIN_RAW" (shape input) (at 334.01 233.68 180) (fields_autoplaced)
    (effects (font (size 1.27 1.27)) (justify right))
    (property "Intersheetrefs" "${INTERSHEET_REFS}" (at 323.8844 233.6006 0)
      (effects (font (size 1.27 1.27)) (justify right) hide)
    )
  )
  (global_label "3V3_SYS" (shape input) (at 315.595 157.48 180) (fields_autoplaced)
    (effects (font (size 1.27 1.27)) (justify right))
    (property "Intersheetrefs" "${INTERSHEET_REFS}" (at 256.54 10.795 0)
      (effects (font (size 1.27 1.27)) hide)
    )
  )
  (global_label "ETH_TX_EN" (shape input) (at 188.595 54.61 180) (fields_autoplaced)
    (effects (font (size 1.27 1.27)) (justify right))
    (property "Intersheetrefs" "${INTERSHEET_REFS}" (at 10.16 -28.575 0)
      (effects (font (size 1.27 1.27)) hide)
    )
  )
  (global_label "ETH_RX_CLK" (shape input) (at 188.595 83.82 180) (fields_autoplaced)
    (effects (font (size 1.27 1.27)) (justify right))
    (property "Intersheetrefs" "${INTERSHEET_REFS}" (at 10.16 -29.845 0)
      (effects (font (size 1.27 1.27)) hide)
    )
  )
  (global_label "ETH_RSTN" (shape input) (at 187.96 41.91 180) (fields_autoplaced)
    (effects (font (size 1.27 1.27)) (justify right))
    (property "Intersheetrefs" "${INTERSHEET_REFS}" (at 10.16 -89.535 0)
      (effects (font (size 1.27 1.27)) hide)
    )
  )
  (global_label "ETH_RXD1" (shape input) (at 188.595 76.2 180) (fields_autoplaced)
    (effects (font (size 1.27 1.27)) (justify right))
    (property "Intersheetrefs" "${INTERSHEET_REFS}" (at 10.16 -29.845 0)
      (effects (font (size 1.27 1.27)) hide)
    )
  )
  (global_label "LED_SPD" (shape input) (at 235.585 78.74 0) (fields_autoplaced)
    (effects (font (size 1.27 1.27)) (justify left))
    (property "Intersheetrefs" "${INTERSHEET_REFS}" (at 414.02 197.485 0)
      (effects (font (size 1.27 1.27)) hide)
    )
  )
  (global_label "ETH_RX_DV" (shape input) (at 231.14 144.78 180) (fields_autoplaced)
    (effects (font (size 1.27 1.27)) (justify right))
    (property "Intersheetrefs" "${INTERSHEET_REFS}" (at -97.155 21.59 0)
      (effects (font (size 1.27 1.27)) hide)
    )
  )
  (global_label "EXT_ETH1_P" (shape input) (at 364.49 25.4 0) (fields_autoplaced)
    (effects (font (size 1.27 1.27)) (justify left))
    (property "Intersheetrefs" "${INTERSHEET_REFS}" (at 378.0023 25.3206 0)
      (effects (font (size 1.27 1.27)) (justify left) hide)
    )
  )
  (global_label "ETH_RXD0" (shape input) (at 172.085 134.62 180) (fields_autoplaced)
    (effects (font (size 1.27 1.27)) (justify right))
    (property "Intersheetrefs" "${INTERSHEET_REFS}" (at -156.21 80.01 0)
      (effects (font (size 1.27 1.27)) (justify right) hide)
    )
  )
  (global_label "3V3_SYS" (shape input) (at 328.295 25.4 180) (fields_autoplaced)
    (effects (font (size 1.27 1.27)) (justify right))
    (property "Intersheetrefs" "${INTERSHEET_REFS}" (at 276.86 236.855 0)
      (effects (font (size 1.27 1.27)) hide)
    )
  )
  (global_label "3V3_SYS" (shape input) (at 201.295 134.62 0) (fields_autoplaced)
    (effects (font (size 1.27 1.27)) (justify left))
    (property "Intersheetrefs" "${INTERSHEET_REFS}" (at 252.095 -218.44 90)
      (effects (font (size 1.27 1.27)) (justify right) hide)
    )
  )
  (global_label "ETH_RX_DV" (shape input) (at 172.085 144.78 180) (fields_autoplaced)
    (effects (font (size 1.27 1.27)) (justify right))
    (property "Intersheetrefs" "${INTERSHEET_REFS}" (at -156.21 80.01 0)
      (effects (font (size 1.27 1.27)) (justify right) hide)
    )
  )
  (global_label "ETH_RXD3" (shape input) (at 188.595 81.28 180) (fields_autoplaced)
    (effects (font (size 1.27 1.27)) (justify right))
    (property "Intersheetrefs" "${INTERSHEET_REFS}" (at 10.16 -29.845 0)
      (effects (font (size 1.27 1.27)) hide)
    )
  )
  (global_label "ETH_REF_CLK" (shape input) (at 231.14 149.86 180) (fields_autoplaced)
    (effects (font (size 1.27 1.27)) (justify right))
    (property "Intersheetrefs" "${INTERSHEET_REFS}" (at -97.155 21.59 0)
      (effects (font (size 1.27 1.27)) hide)
    )
  )
  (global_label "INT_LED_SPD" (shape input) (at 96.52 237.49 0) (fields_autoplaced)
    (effects (font (size 1.27 1.27)) (justify left))
    (property "Intersheetrefs" "${INTERSHEET_REFS}" (at 110.879 237.4106 0)
      (effects (font (size 1.27 1.27)) (justify left) hide)
    )
  )
  (global_label "ETH_MDIO" (shape input) (at 172.085 157.48 180) (fields_autoplaced)
    (effects (font (size 1.27 1.27)) (justify right))
    (property "Intersheetrefs" "${INTERSHEET_REFS}" (at -156.21 80.01 0)
      (effects (font (size 1.27 1.27)) (justify right) hide)
    )
  )
  (global_label "LED_SPD" (shape input) (at 172.085 152.4 180) (fields_autoplaced)
    (effects (font (size 1.27 1.27)) (justify right))
    (property "Intersheetrefs" "${INTERSHEET_REFS}" (at -156.21 80.01 0)
      (effects (font (size 1.27 1.27)) (justify right) hide)
    )
  )
  (global_label "EXT_ETH1_N" (shape input) (at 364.49 27.94 0) (fields_autoplaced)
    (effects (font (size 1.27 1.27)) (justify left))
    (property "Intersheetrefs" "${INTERSHEET_REFS}" (at 378.0628 27.8606 0)
      (effects (font (size 1.27 1.27)) (justify left) hide)
    )
  )
  (global_label "ETH_RXD3" (shape input) (at 231.14 142.24 180) (fields_autoplaced)
    (effects (font (size 1.27 1.27)) (justify right))
    (property "Intersheetrefs" "${INTERSHEET_REFS}" (at -97.155 21.59 0)
      (effects (font (size 1.27 1.27)) hide)
    )
  )
  (global_label "LED_LINK" (shape input) (at 231.14 154.94 180) (fields_autoplaced)
    (effects (font (size 1.27 1.27)) (justify right))
    (property "Intersheetrefs" "${INTERSHEET_REFS}" (at -97.155 21.59 0)
      (effects (font (size 1.27 1.27)) hide)
    )
  )
  (global_label "3V3_SYS" (shape input) (at 87.63 219.075 180) (fields_autoplaced)
    (effects (font (size 1.27 1.27)) (justify right))
    (property "Intersheetrefs" "${INTERSHEET_REFS}" (at -127 450.85 90)
      (effects (font (size 1.27 1.27)) (justify right) hide)
    )
  )
  (global_label "ETH_REF_CLK" (shape input) (at 187.96 87.63 180) (fields_autoplaced)
    (effects (font (size 1.27 1.27)) (justify right))
    (property "Intersheetrefs" "${INTERSHEET_REFS}" (at 10.16 -41.275 0)
      (effects (font (size 1.27 1.27)) hide)
    )
  )
  (global_label "3V3_SYS" (shape input) (at 26.035 88.9 180) (fields_autoplaced)
    (effects (font (size 1.27 1.27)) (justify right))
    (property "Intersheetrefs" "${INTERSHEET_REFS}" (at -33.02 -57.785 0)
      (effects (font (size 1.27 1.27)) hide)
    )
  )
  (global_label "1V2_SYS" (shape input) (at 40.005 32.385 180) (fields_autoplaced)
    (effects (font (size 1.27 1.27)) (justify right))
    (property "Intersheetrefs" "${INTERSHEET_REFS}" (at 6.985 76.835 0)
      (effects (font (size 1.27 1.27)) hide)
    )
  )
  (global_label "EXT_LED_SPD" (shape input) (at 364.49 55.88 0) (fields_autoplaced)
    (effects (font (size 1.27 1.27)) (justify left))
    (property "Intersheetrefs" "${INTERSHEET_REFS}" (at 379.2723 55.8006 0)
      (effects (font (size 1.27 1.27)) (justify left) hide)
    )
  )
  (global_label "ETH_RX_DV" (shape input) (at 188.595 71.12 180) (fields_autoplaced)
    (effects (font (size 1.27 1.27)) (justify right))
    (property "Intersheetrefs" "${INTERSHEET_REFS}" (at 10.16 -29.845 0)
      (effects (font (size 1.27 1.27)) hide)
    )
  )
  (global_label "EXT_ETH2_N" (shape input) (at 364.49 34.29 0) (fields_autoplaced)
    (effects (font (size 1.27 1.27)) (justify left))
    (property "Intersheetrefs" "${INTERSHEET_REFS}" (at 378.0628 34.2106 0)
      (effects (font (size 1.27 1.27)) (justify left) hide)
    )
  )
  (global_label "1V2_SYS" (shape input) (at 90.17 88.9 180) (fields_autoplaced)
    (effects (font (size 1.27 1.27)) (justify right))
    (property "Intersheetrefs" "${INTERSHEET_REFS}" (at 182.245 -114.3 0)
      (effects (font (size 1.27 1.27)) (justify left) hide)
    )
  )
  (global_label "VIN" (shape output) (at 400.05 199.39 0) (fields_autoplaced)
    (effects (font (size 1.27 1.27)) (justify left))
    (property "Intersheetrefs" "${INTERSHEET_REFS}" (at 405.398 199.3106 0)
      (effects (font (size 1.27 1.27)) (justify left) hide)
    )
  )
  (global_label "ETH_TXD0" (shape input) (at 188.595 57.15 180) (fields_autoplaced)
    (effects (font (size 1.27 1.27)) (justify right))
    (property "Intersheetrefs" "${INTERSHEET_REFS}" (at 10.16 -28.575 0)
      (effects (font (size 1.27 1.27)) hide)
    )
  )
  (global_label "LED_LINK" (shape input) (at 235.585 76.2 0) (fields_autoplaced)
    (effects (font (size 1.27 1.27)) (justify left))
    (property "Intersheetrefs" "${INTERSHEET_REFS}" (at 414.02 197.485 0)
      (effects (font (size 1.27 1.27)) hide)
    )
  )
  (global_label "LED_LINK" (shape input) (at 328.295 77.47 180) (fields_autoplaced)
    (effects (font (size 1.27 1.27)) (justify right))
    (property "Intersheetrefs" "${INTERSHEET_REFS}" (at 149.86 198.755 0)
      (effects (font (size 1.27 1.27)) hide)
    )
  )
  (global_label "ETH_RXD3" (shape input) (at 172.085 142.24 180) (fields_autoplaced)
    (effects (font (size 1.27 1.27)) (justify right))
    (property "Intersheetrefs" "${INTERSHEET_REFS}" (at -156.21 80.01 0)
      (effects (font (size 1.27 1.27)) (justify right) hide)
    )
  )
  (global_label "ETH_RX_CLK" (shape input) (at 172.085 147.32 180) (fields_autoplaced)
    (effects (font (size 1.27 1.27)) (justify right))
    (property "Intersheetrefs" "${INTERSHEET_REFS}" (at -156.21 80.01 0)
      (effects (font (size 1.27 1.27)) (justify right) hide)
    )
  )
  (global_label "1V2_SYS" (shape input) (at 23.495 140.97 180) (fields_autoplaced)
    (effects (font (size 1.27 1.27)) (justify right))
    (property "Intersheetrefs" "${INTERSHEET_REFS}" (at 135.89 -106.045 0)
      (effects (font (size 1.27 1.27)) (justify left) hide)
    )
  )
  (global_label "ETH_TX_CLK" (shape input) (at 188.595 67.31 180) (fields_autoplaced)
    (effects (font (size 1.27 1.27)) (justify right))
    (property "Intersheetrefs" "${INTERSHEET_REFS}" (at 10.16 -28.575 0)
      (effects (font (size 1.27 1.27)) hide)
    )
  )

  (symbol (lib_id "antmicroCapacitors0402:C_22p_0402") (at 180.34 104.14 90) (mirror x) (unit 1)
    (in_bom yes) (on_board yes) (dnp no) (fields_autoplaced)
    (property "Reference" "C147" (at 182.88 105.4163 90)
      (effects (font (size 1.524 1.524)) (justify right))
    )
    (property "Value" "C_22p_0402" (at 190.5 124.46 0)
      (effects (font (size 1.27 1.27) (thickness 0.15)) (justify left bottom) hide)
    )
    (property "Footprint" "antmicro-footprints:C_0402_1005Metric" (at 193.04 124.46 0)
      (effects (font (size 1.27 1.27) (thickness 0.15)) (justify left bottom) hide)
    )
    (property "Datasheet" " " (at 195.58 124.46 0)
      (effects (font (size 1.27 1.27) (thickness 0.15)) (justify left bottom) hide)
    )
    (property "Manufacturer" "Yaego" (at 200.66 124.46 0)
      (effects (font (size 1.27 1.27) (thickness 0.15)) (justify left bottom) hide)
    )
    (property "MPN" "CC0402JRNPO9BN220" (at 198.12 124.46 0)
      (effects (font (size 1.27 1.27) (thickness 0.15)) (justify left bottom) hide)
    )
    (property "Val" "22p" (at 182.88 108.5912 90)
      (effects (font (size 1.27 1.27) (thickness 0.15)) (justify right))
    )
    (property "License" "Apache-2.0" (at 203.2 124.46 0)
      (effects (font (size 1.27 1.27) (thickness 0.15)) (justify left bottom) hide)
    )
    (property "Author" "Antmicro" (at 205.74 124.46 0)
      (effects (font (size 1.27 1.27) (thickness 0.15)) (justify left bottom) hide)
    )
    (property "Voltage" "" (at 208.28 124.46 0)
      (effects (font (size 1.27 1.27)) (justify left bottom) hide)
    )
    (property "Dielectric" "" (at 210.82 124.46 0)
      (effects (font (size 1.27 1.27)) (justify left bottom) hide)
    )
    (pin "1")
    (pin "2")
    (instances
      (project "data-center-rdimm-ddr4-tester"
        (path ""
          (reference "C147") (unit 1)
        )
      )
    )
  )

  (symbol (lib_id "antmicroCapacitors0402:C_22p_0402") (at 167.005 104.14 90) (mirror x) (unit 1)
    (in_bom yes) (on_board yes) (dnp no) (fields_autoplaced)
    (property "Reference" "C148" (at 164.465 105.4163 90)
      (effects (font (size 1.524 1.524)) (justify left))
    )
    (property "Value" "C_22p_0402" (at 177.165 124.46 0)
      (effects (font (size 1.27 1.27) (thickness 0.15)) (justify left bottom) hide)
    )
    (property "Footprint" "antmicro-footprints:C_0402_1005Metric" (at 179.705 124.46 0)
      (effects (font (size 1.27 1.27) (thickness 0.15)) (justify left bottom) hide)
    )
    (property "Datasheet" " " (at 182.245 124.46 0)
      (effects (font (size 1.27 1.27) (thickness 0.15)) (justify left bottom) hide)
    )
    (property "Manufacturer" "Yaego" (at 187.325 124.46 0)
      (effects (font (size 1.27 1.27) (thickness 0.15)) (justify left bottom) hide)
    )
    (property "MPN" "CC0402JRNPO9BN220" (at 184.785 124.46 0)
      (effects (font (size 1.27 1.27) (thickness 0.15)) (justify left bottom) hide)
    )
    (property "Val" "22p" (at 164.465 108.5912 90)
      (effects (font (size 1.27 1.27) (thickness 0.15)) (justify left))
    )
    (property "License" "Apache-2.0" (at 189.865 124.46 0)
      (effects (font (size 1.27 1.27) (thickness 0.15)) (justify left bottom) hide)
    )
    (property "Author" "Antmicro" (at 192.405 124.46 0)
      (effects (font (size 1.27 1.27) (thickness 0.15)) (justify left bottom) hide)
    )
    (property "Voltage" "" (at 194.945 124.46 0)
      (effects (font (size 1.27 1.27)) (justify left bottom) hide)
    )
    (property "Dielectric" "" (at 197.485 124.46 0)
      (effects (font (size 1.27 1.27)) (justify left bottom) hide)
    )
    (pin "1")
    (pin "2")
    (instances
      (project "data-center-rdimm-ddr4-tester"
        (path ""
          (reference "C148") (unit 1)
        )
      )
    )
  )

  (symbol (lib_id "data-center-rdimm-ddr4-tester:Oscillator_SMD_25MHz_KX-7") (at 177.8 102.87 0) (mirror y) (unit 1)
    (in_bom yes) (on_board yes) (dnp no)
    (property "Reference" "Y1" (at 172.72 97.155 0)
      (effects (font (size 1.4986 1.4986)))
    )
    (property "Value" "Oscillator_SMD_25MHz_KX-7" (at 173.99 97.155 0)
      (effects (font (size 1.27 1.27) (thickness 0.15)) hide)
    )
    (property "Footprint" "data-center-rdimm-ddr4-tester-footprints:Oscillator_SMD_Geyer_KX-7-4Pin_3.2x2.5mm" (at 154.94 113.03 0)
      (effects (font (size 1.27 1.27) (thickness 0.15)) (justify left bottom) hide)
    )
    (property "Datasheet" "" (at 154.94 115.57 0)
      (effects (font (size 1.27 1.27) (thickness 0.15)) (justify left bottom) hide)
    )
    (property "MPN" "ABM8G-25.000MHZ-18-D2Y-T" (at 174.625 99.06 0)
      (effects (font (size 1.27 1.27) (thickness 0.15)))
    )
    (property "Manufacturer" "Abracon" (at 154.94 120.65 0)
      (effects (font (size 1.27 1.27) (thickness 0.15)) (justify left bottom) hide)
    )
    (property "Val" "25MHz" (at 154.94 123.19 0)
      (effects (font (size 1.27 1.27) (thickness 0.15)) (justify left bottom) hide)
    )
    (property "Author" "Antmicro" (at 154.94 125.73 0)
      (effects (font (size 1.27 1.27) (thickness 0.15)) (justify left bottom) hide)
    )
    (property "License" "Apache-2.0" (at 154.94 128.27 0)
      (effects (font (size 1.27 1.27) (thickness 0.15)) (justify left bottom) hide)
    )
    (pin "1")
    (pin "2")
    (pin "3")
    (pin "4")
    (instances
      (project "data-center-rdimm-ddr4-tester"
        (path ""
          (reference "Y1") (unit 1)
        )
      )
    )
  )

  (symbol (lib_id "antmicroResistors0402:R_1M8_0402") (at 176.53 93.98 0) (mirror y) (unit 1)
    (in_bom yes) (on_board yes) (dnp no)
    (property "Reference" "R69" (at 169.545 92.71 0)
      (effects (font (size 1.524 1.524)))
    )
    (property "Value" "R_1M8_0402" (at 156.21 106.68 0)
      (effects (font (size 1.27 1.27) (thickness 0.15)) (justify left bottom) hide)
    )
    (property "Footprint" "antmicro-footprints:R_0402_1005Metric" (at 156.21 109.22 0)
      (effects (font (size 1.27 1.27) (thickness 0.15)) (justify left bottom) hide)
    )
    (property "Datasheet" "https://www.bourns.com/docs/product-datasheets/cr.pdf" (at 156.21 111.76 0)
      (effects (font (size 1.27 1.27) (thickness 0.15)) (justify left bottom) hide)
    )
    (property "Manufacturer" "Bourns" (at 156.21 116.84 0)
      (effects (font (size 1.27 1.27) (thickness 0.15)) (justify left bottom) hide)
    )
    (property "MPN" "CR0402-FX-1804GLF" (at 156.21 114.3 0)
      (effects (font (size 1.27 1.27) (thickness 0.15)) (justify left bottom) hide)
    )
    (property "Val" "1M8" (at 178.435 92.71 0)
      (effects (font (size 1.27 1.27) (thickness 0.15)))
    )
    (property "License" "Apache-2.0" (at 156.21 119.38 0)
      (effects (font (size 1.27 1.27) (thickness 0.15)) (justify left bottom) hide)
    )
    (property "Author" "Antmicro" (at 156.21 121.92 0)
      (effects (font (size 1.27 1.27) (thickness 0.15)) (justify left bottom) hide)
    )
    (property "Tolerance" "1%" (at 156.21 104.14 0)
      (effects (font (size 1.27 1.27)) (justify left bottom) hide)
    )
    (pin "1")
    (pin "2")
    (instances
      (project "data-center-rdimm-ddr4-tester"
        (path ""
          (reference "R69") (unit 1)
        )
      )
    )
  )

  (symbol (lib_id "antmicroInterfaceControllers:KSZ9031RNXCA") (at 189.865 34.29 0) (unit 1)
    (in_bom yes) (on_board yes) (dnp no) (fields_autoplaced)
    (property "Reference" "U6" (at 212.09 26.67 0)
      (effects (font (size 1.27 1.27)))
    )
    (property "Value" "KSZ9031RNXCA" (at 212.09 29.21 0)
      (effects (font (size 1.27 1.27) (thickness 0.15)))
    )
    (property "Footprint" "antmicro-footprints:QFN-48-1EP_7x7x0.9mm_P0.5mm_EP3.5x3.5mm" (at 266.065 44.45 0)
      (effects (font (size 1.27 1.27) (thickness 0.15)) (justify left bottom) hide)
    )
    (property "Datasheet" "http://ww1.microchip.com/downloads/en/DeviceDoc/00002117F.pdf" (at 266.065 46.99 0)
      (effects (font (size 1.27 1.27) (thickness 0.15)) (justify left bottom) hide)
    )
    (property "Manufacturer" "Microchip Technology" (at 266.065 49.53 0)
      (effects (font (size 1.27 1.27) (thickness 0.15)) (justify left bottom) hide)
    )
    (property "MPN" "KSZ9031RNXCA" (at 266.065 52.07 0)
      (effects (font (size 1.27 1.27) (thickness 0.15)) (justify left bottom) hide)
    )
    (property "Author" "Antmicro" (at 266.065 54.61 0)
      (effects (font (size 1.27 1.27) (thickness 0.15)) (justify left bottom) hide)
    )
    (property "License" "Apache-2.0" (at 266.065 57.15 0)
      (effects (font (size 1.27 1.27) (thickness 0.15)) (justify left bottom) hide)
    )
    (pin "1")
    (pin "10")
    (pin "11")
    (pin "12")
    (pin "13")
    (pin "14")
    (pin "15")
    (pin "16")
    (pin "17")
    (pin "18")
    (pin "19")
    (pin "2")
    (pin "20")
    (pin "21")
    (pin "22")
    (pin "23")
    (pin "24")
    (pin "25")
    (pin "26")
    (pin "27")
    (pin "28")
    (pin "29")
    (pin "3")
    (pin "30")
    (pin "31")
    (pin "32")
    (pin "33")
    (pin "34")
    (pin "35")
    (pin "36")
    (pin "37")
    (pin "38")
    (pin "39")
    (pin "4")
    (pin "40")
    (pin "41")
    (pin "42")
    (pin "43")
    (pin "44")
    (pin "45")
    (pin "46")
    (pin "47")
    (pin "48")
    (pin "49")
    (pin "5")
    (pin "6")
    (pin "7")
    (pin "8")
    (pin "9")
    (instances
      (project "data-center-rdimm-ddr4-tester"
        (path ""
          (reference "U6") (unit 1)
        )
      )
    )
  )

  (symbol (lib_id "antmicroResistors0402:R_12k1_0402") (at 236.22 90.17 90) (unit 1)
    (in_bom yes) (on_board yes) (dnp no) (fields_autoplaced)
    (property "Reference" "R68" (at 238.76 86.36 90)
      (effects (font (size 1.524 1.524)) (justify right))
    )
    (property "Value" "R_12k1_0402" (at 248.92 69.85 0)
      (effects (font (size 1.27 1.27) (thickness 0.15)) (justify left bottom) hide)
    )
    (property "Footprint" "antmicro-footprints:R_0402_1005Metric" (at 251.46 69.85 0)
      (effects (font (size 1.27 1.27) (thickness 0.15)) (justify left bottom) hide)
    )
    (property "Datasheet" "https://www.bourns.com/docs/product-datasheets/cr.pdf" (at 254 69.85 0)
      (effects (font (size 1.27 1.27) (thickness 0.15)) (justify left bottom) hide)
    )
    (property "Manufacturer" "Bourns" (at 259.08 69.85 0)
      (effects (font (size 1.27 1.27) (thickness 0.15)) (justify left bottom) hide)
    )
    (property "MPN" "CR0402-FX-1212GLF" (at 256.54 69.85 0)
      (effects (font (size 1.27 1.27) (thickness 0.15)) (justify left bottom) hide)
    )
    (property "Val" "12k1" (at 238.76 89.5349 90)
      (effects (font (size 1.27 1.27) (thickness 0.15)) (justify right))
    )
    (property "License" "Apache-2.0" (at 261.62 69.85 0)
      (effects (font (size 1.27 1.27) (thickness 0.15)) (justify left bottom) hide)
    )
    (property "Author" "Antmicro" (at 264.16 69.85 0)
      (effects (font (size 1.27 1.27) (thickness 0.15)) (justify left bottom) hide)
    )
    (property "Tolerance" "1%" (at 246.38 69.85 0)
      (effects (font (size 1.27 1.27)) (justify left bottom) hide)
    )
    (pin "1")
    (pin "2")
    (instances
      (project "data-center-rdimm-ddr4-tester"
        (path ""
          (reference "R68") (unit 1)
        )
      )
    )
  )

  (symbol (lib_id "antmicropower:GND") (at 236.22 95.885 0) (unit 1)
    (in_bom yes) (on_board yes) (dnp no) (fields_autoplaced)
    (property "Reference" "#PWR043" (at 236.22 102.235 0)
      (effects (font (size 1.27 1.27)) hide)
    )
    (property "Value" "GND" (at 236.22 100.33 0)
      (effects (font (size 1.27 1.27)))
    )
    (property "Footprint" "" (at 236.22 95.885 0)
      (effects (font (size 1.27 1.27)) hide)
    )
    (property "Datasheet" "" (at 236.22 95.885 0)
      (effects (font (size 1.27 1.27)) hide)
    )
    (property "Author" "Antmicro" (at 245.11 103.505 0)
      (effects (font (size 1.27 1.27) (thickness 0.15)) (justify left bottom) hide)
    )
    (property "License" "Apache-2.0" (at 245.11 106.045 0)
      (effects (font (size 1.27 1.27) (thickness 0.15)) (justify left bottom) hide)
    )
    (pin "1")
    (instances
      (project "data-center-rdimm-ddr4-tester"
        (path ""
          (reference "#PWR043") (unit 1)
        )
      )
    )
  )

  (symbol (lib_id "antmicropower:GND") (at 173.99 113.03 0) (mirror y) (unit 1)
    (in_bom yes) (on_board yes) (dnp no) (fields_autoplaced)
    (property "Reference" "#PWR044" (at 173.99 119.38 0)
      (effects (font (size 1.27 1.27)) hide)
    )
    (property "Value" "GND" (at 173.99 118.11 0)
      (effects (font (size 1.27 1.27)))
    )
    (property "Footprint" "" (at 173.99 113.03 0)
      (effects (font (size 1.27 1.27)) hide)
    )
    (property "Datasheet" "" (at 173.99 113.03 0)
      (effects (font (size 1.27 1.27)) hide)
    )
    (property "Author" "Antmicro" (at 165.1 120.65 0)
      (effects (font (size 1.27 1.27) (thickness 0.15)) (justify left bottom) hide)
    )
    (property "License" "Apache-2.0" (at 165.1 123.19 0)
      (effects (font (size 1.27 1.27) (thickness 0.15)) (justify left bottom) hide)
    )
    (pin "1")
    (instances
      (project "data-center-rdimm-ddr4-tester"
        (path ""
          (reference "#PWR044") (unit 1)
        )
      )
    )
  )

  (symbol (lib_id "antmicroCapacitors0402:C_4u7_0402") (at 59.69 142.875 90) (mirror x) (unit 1)
    (in_bom yes) (on_board yes) (dnp no)
    (property "Reference" "C121" (at 60.325 143.51 90)
      (effects (font (size 1.524 1.524)) (justify right))
    )
    (property "Value" "C_4u7_0402" (at 69.85 163.195 0)
      (effects (font (size 1.27 1.27) (thickness 0.15)) (justify left bottom) hide)
    )
    (property "Footprint" "antmicro-footprints:C_0402_1005Metric" (at 72.39 163.195 0)
      (effects (font (size 1.27 1.27) (thickness 0.15)) (justify left bottom) hide)
    )
    (property "Datasheet" " " (at 74.93 163.195 0)
      (effects (font (size 1.27 1.27) (thickness 0.15)) (justify left bottom) hide)
    )
    (property "Manufacturer" "Murata" (at 80.01 163.195 0)
      (effects (font (size 1.27 1.27) (thickness 0.15)) (justify left bottom) hide)
    )
    (property "MPN" "GRM155R61A475MEAAD" (at 77.47 163.195 0)
      (effects (font (size 1.27 1.27) (thickness 0.15)) (justify left bottom) hide)
    )
    (property "Val" "4u7" (at 60.325 147.32 90)
      (effects (font (size 1.27 1.27) (thickness 0.15)) (justify right))
    )
    (property "License" "Apache-2.0" (at 82.55 163.195 0)
      (effects (font (size 1.27 1.27) (thickness 0.15)) (justify left bottom) hide)
    )
    (property "Author" "Antmicro" (at 85.09 163.195 0)
      (effects (font (size 1.27 1.27) (thickness 0.15)) (justify left bottom) hide)
    )
    (property "Voltage" "" (at 87.63 163.195 0)
      (effects (font (size 1.27 1.27)) (justify left bottom) hide)
    )
    (property "Dielectric" "" (at 90.17 163.195 0)
      (effects (font (size 1.27 1.27)) (justify left bottom) hide)
    )
    (pin "1")
    (pin "2")
    (instances
      (project "data-center-rdimm-ddr4-tester"
        (path ""
          (reference "C121") (unit 1)
        )
      )
    )
  )

  (symbol (lib_id "antmicroCapacitors0402:C_470n_0402") (at 51.435 142.875 90) (mirror x) (unit 1)
    (in_bom yes) (on_board yes) (dnp no)
    (property "Reference" "C125" (at 52.07 143.51 90)
      (effects (font (size 1.524 1.524)) (justify right))
    )
    (property "Value" "C_470n_0402" (at 61.595 163.195 0)
      (effects (font (size 1.27 1.27) (thickness 0.15)) (justify left bottom) hide)
    )
    (property "Footprint" "antmicro-footprints:C_0402_1005Metric" (at 64.135 163.195 0)
      (effects (font (size 1.27 1.27) (thickness 0.15)) (justify left bottom) hide)
    )
    (property "Datasheet" " " (at 66.675 163.195 0)
      (effects (font (size 1.27 1.27) (thickness 0.15)) (justify left bottom) hide)
    )
    (property "Manufacturer" "TDK" (at 71.755 163.195 0)
      (effects (font (size 1.27 1.27) (thickness 0.15)) (justify left bottom) hide)
    )
    (property "MPN" "C1005X5R1E474M050BB" (at 69.215 163.195 0)
      (effects (font (size 1.27 1.27) (thickness 0.15)) (justify left bottom) hide)
    )
    (property "Val" "470n" (at 52.07 147.32 90)
      (effects (font (size 1.27 1.27) (thickness 0.15)) (justify right))
    )
    (property "License" "Apache-2.0" (at 74.295 163.195 0)
      (effects (font (size 1.27 1.27) (thickness 0.15)) (justify left bottom) hide)
    )
    (property "Author" "Antmicro" (at 76.835 163.195 0)
      (effects (font (size 1.27 1.27) (thickness 0.15)) (justify left bottom) hide)
    )
    (property "Voltage" "" (at 79.375 163.195 0)
      (effects (font (size 1.27 1.27)) (justify left bottom) hide)
    )
    (property "Dielectric" "" (at 81.915 163.195 0)
      (effects (font (size 1.27 1.27)) (justify left bottom) hide)
    )
    (pin "1")
    (pin "2")
    (instances
      (project "data-center-rdimm-ddr4-tester"
        (path ""
          (reference "C125") (unit 1)
        )
      )
    )
  )

  (symbol (lib_id "antmicroCapacitors0402:C_10n_0402") (at 43.18 142.875 90) (mirror x) (unit 1)
    (in_bom yes) (on_board yes) (dnp no)
    (property "Reference" "C129" (at 43.815 143.51 90)
      (effects (font (size 1.524 1.524)) (justify right))
    )
    (property "Value" "C_10n_0402" (at 53.34 163.195 0)
      (effects (font (size 1.27 1.27) (thickness 0.15)) (justify left bottom) hide)
    )
    (property "Footprint" "antmicro-footprints:C_0402_1005Metric" (at 55.88 163.195 0)
      (effects (font (size 1.27 1.27) (thickness 0.15)) (justify left bottom) hide)
    )
    (property "Datasheet" "https://search.murata.co.jp/Ceramy/image/img/A01X/G101/ENG/GRM155R71H103KA88-01.pdf" (at 58.42 163.195 0)
      (effects (font (size 1.27 1.27) (thickness 0.15)) (justify left bottom) hide)
    )
    (property "Manufacturer" "Murata" (at 63.5 163.195 0)
      (effects (font (size 1.27 1.27) (thickness 0.15)) (justify left bottom) hide)
    )
    (property "MPN" "GRM155R71H103KA88D" (at 60.96 163.195 0)
      (effects (font (size 1.27 1.27) (thickness 0.15)) (justify left bottom) hide)
    )
    (property "Val" "10n" (at 43.815 147.32 90)
      (effects (font (size 1.27 1.27) (thickness 0.15)) (justify right))
    )
    (property "License" "Apache-2.0" (at 66.04 163.195 0)
      (effects (font (size 1.27 1.27) (thickness 0.15)) (justify left bottom) hide)
    )
    (property "Author" "Antmicro" (at 68.58 163.195 0)
      (effects (font (size 1.27 1.27) (thickness 0.15)) (justify left bottom) hide)
    )
    (property "Voltage" "50V" (at 71.12 163.195 0)
      (effects (font (size 1.27 1.27)) (justify left bottom) hide)
    )
    (property "Dielectric" "X7R" (at 73.66 163.195 0)
      (effects (font (size 1.27 1.27)) (justify left bottom) hide)
    )
    (pin "1")
    (pin "2")
    (instances
      (project "data-center-rdimm-ddr4-tester"
        (path ""
          (reference "C129") (unit 1)
        )
      )
    )
  )

  (symbol (lib_id "antmicroCapacitors0402:C_10n_0402") (at 34.925 142.875 90) (mirror x) (unit 1)
    (in_bom yes) (on_board yes) (dnp no)
    (property "Reference" "C134" (at 35.56 143.51 90)
      (effects (font (size 1.524 1.524)) (justify right))
    )
    (property "Value" "C_10n_0402" (at 45.085 163.195 0)
      (effects (font (size 1.27 1.27) (thickness 0.15)) (justify left bottom) hide)
    )
    (property "Footprint" "antmicro-footprints:C_0402_1005Metric" (at 47.625 163.195 0)
      (effects (font (size 1.27 1.27) (thickness 0.15)) (justify left bottom) hide)
    )
    (property "Datasheet" "https://search.murata.co.jp/Ceramy/image/img/A01X/G101/ENG/GRM155R71H103KA88-01.pdf" (at 50.165 163.195 0)
      (effects (font (size 1.27 1.27) (thickness 0.15)) (justify left bottom) hide)
    )
    (property "Manufacturer" "Murata" (at 55.245 163.195 0)
      (effects (font (size 1.27 1.27) (thickness 0.15)) (justify left bottom) hide)
    )
    (property "MPN" "GRM155R71H103KA88D" (at 52.705 163.195 0)
      (effects (font (size 1.27 1.27) (thickness 0.15)) (justify left bottom) hide)
    )
    (property "Val" "10n" (at 35.56 147.32 90)
      (effects (font (size 1.27 1.27) (thickness 0.15)) (justify right))
    )
    (property "License" "Apache-2.0" (at 57.785 163.195 0)
      (effects (font (size 1.27 1.27) (thickness 0.15)) (justify left bottom) hide)
    )
    (property "Author" "Antmicro" (at 60.325 163.195 0)
      (effects (font (size 1.27 1.27) (thickness 0.15)) (justify left bottom) hide)
    )
    (property "Voltage" "50V" (at 62.865 163.195 0)
      (effects (font (size 1.27 1.27)) (justify left bottom) hide)
    )
    (property "Dielectric" "X7R" (at 65.405 163.195 0)
      (effects (font (size 1.27 1.27)) (justify left bottom) hide)
    )
    (pin "1")
    (pin "2")
    (instances
      (project "data-center-rdimm-ddr4-tester"
        (path ""
          (reference "C134") (unit 1)
        )
      )
    )
  )

  (symbol (lib_id "antmicroCapacitors0402:C_10n_0402") (at 100.965 34.925 270) (unit 1)
    (in_bom yes) (on_board yes) (dnp no)
    (property "Reference" "C141" (at 101.6 35.56 90)
      (effects (font (size 1.524 1.524)) (justify left))
    )
    (property "Value" "C_10n_0402" (at 90.805 55.245 0)
      (effects (font (size 1.27 1.27) (thickness 0.15)) (justify left bottom) hide)
    )
    (property "Footprint" "antmicro-footprints:C_0402_1005Metric" (at 88.265 55.245 0)
      (effects (font (size 1.27 1.27) (thickness 0.15)) (justify left bottom) hide)
    )
    (property "Datasheet" "https://search.murata.co.jp/Ceramy/image/img/A01X/G101/ENG/GRM155R71H103KA88-01.pdf" (at 85.725 55.245 0)
      (effects (font (size 1.27 1.27) (thickness 0.15)) (justify left bottom) hide)
    )
    (property "Manufacturer" "Murata" (at 80.645 55.245 0)
      (effects (font (size 1.27 1.27) (thickness 0.15)) (justify left bottom) hide)
    )
    (property "MPN" "GRM155R71H103KA88D" (at 83.185 55.245 0)
      (effects (font (size 1.27 1.27) (thickness 0.15)) (justify left bottom) hide)
    )
    (property "Val" "10n" (at 101.6 39.37 90)
      (effects (font (size 1.27 1.27) (thickness 0.15)) (justify left))
    )
    (property "License" "Apache-2.0" (at 78.105 55.245 0)
      (effects (font (size 1.27 1.27) (thickness 0.15)) (justify left bottom) hide)
    )
    (property "Author" "Antmicro" (at 75.565 55.245 0)
      (effects (font (size 1.27 1.27) (thickness 0.15)) (justify left bottom) hide)
    )
    (property "Voltage" "50V" (at 73.025 55.245 0)
      (effects (font (size 1.27 1.27)) (justify left bottom) hide)
    )
    (property "Dielectric" "X7R" (at 70.485 55.245 0)
      (effects (font (size 1.27 1.27)) (justify left bottom) hide)
    )
    (pin "1")
    (pin "2")
    (instances
      (project "data-center-rdimm-ddr4-tester"
        (path ""
          (reference "C141") (unit 1)
        )
      )
    )
  )

  (symbol (lib_id "antmicroCapacitors0402:C_10n_0402") (at 109.22 34.925 270) (unit 1)
    (in_bom yes) (on_board yes) (dnp no)
    (property "Reference" "C142" (at 109.855 35.56 90)
      (effects (font (size 1.524 1.524)) (justify left))
    )
    (property "Value" "C_10n_0402" (at 99.06 55.245 0)
      (effects (font (size 1.27 1.27) (thickness 0.15)) (justify left bottom) hide)
    )
    (property "Footprint" "antmicro-footprints:C_0402_1005Metric" (at 96.52 55.245 0)
      (effects (font (size 1.27 1.27) (thickness 0.15)) (justify left bottom) hide)
    )
    (property "Datasheet" "https://search.murata.co.jp/Ceramy/image/img/A01X/G101/ENG/GRM155R71H103KA88-01.pdf" (at 93.98 55.245 0)
      (effects (font (size 1.27 1.27) (thickness 0.15)) (justify left bottom) hide)
    )
    (property "Manufacturer" "Murata" (at 88.9 55.245 0)
      (effects (font (size 1.27 1.27) (thickness 0.15)) (justify left bottom) hide)
    )
    (property "MPN" "GRM155R71H103KA88D" (at 91.44 55.245 0)
      (effects (font (size 1.27 1.27) (thickness 0.15)) (justify left bottom) hide)
    )
    (property "Val" "10n" (at 109.855 39.37 90)
      (effects (font (size 1.27 1.27) (thickness 0.15)) (justify left))
    )
    (property "License" "Apache-2.0" (at 86.36 55.245 0)
      (effects (font (size 1.27 1.27) (thickness 0.15)) (justify left bottom) hide)
    )
    (property "Author" "Antmicro" (at 83.82 55.245 0)
      (effects (font (size 1.27 1.27) (thickness 0.15)) (justify left bottom) hide)
    )
    (property "Voltage" "50V" (at 81.28 55.245 0)
      (effects (font (size 1.27 1.27)) (justify left bottom) hide)
    )
    (property "Dielectric" "X7R" (at 78.74 55.245 0)
      (effects (font (size 1.27 1.27)) (justify left bottom) hide)
    )
    (pin "1")
    (pin "2")
    (instances
      (project "data-center-rdimm-ddr4-tester"
        (path ""
          (reference "C142") (unit 1)
        )
      )
    )
  )

  (symbol (lib_id "antmicroCapacitors0402:C_10n_0402") (at 84.455 34.925 270) (unit 1)
    (in_bom yes) (on_board yes) (dnp no)
    (property "Reference" "C135" (at 85.09 35.56 90)
      (effects (font (size 1.524 1.524)) (justify left))
    )
    (property "Value" "C_10n_0402" (at 74.295 55.245 0)
      (effects (font (size 1.27 1.27) (thickness 0.15)) (justify left bottom) hide)
    )
    (property "Footprint" "antmicro-footprints:C_0402_1005Metric" (at 71.755 55.245 0)
      (effects (font (size 1.27 1.27) (thickness 0.15)) (justify left bottom) hide)
    )
    (property "Datasheet" "https://search.murata.co.jp/Ceramy/image/img/A01X/G101/ENG/GRM155R71H103KA88-01.pdf" (at 69.215 55.245 0)
      (effects (font (size 1.27 1.27) (thickness 0.15)) (justify left bottom) hide)
    )
    (property "Manufacturer" "Murata" (at 64.135 55.245 0)
      (effects (font (size 1.27 1.27) (thickness 0.15)) (justify left bottom) hide)
    )
    (property "MPN" "GRM155R71H103KA88D" (at 66.675 55.245 0)
      (effects (font (size 1.27 1.27) (thickness 0.15)) (justify left bottom) hide)
    )
    (property "Val" "10n" (at 85.09 39.37 90)
      (effects (font (size 1.27 1.27) (thickness 0.15)) (justify left))
    )
    (property "License" "Apache-2.0" (at 61.595 55.245 0)
      (effects (font (size 1.27 1.27) (thickness 0.15)) (justify left bottom) hide)
    )
    (property "Author" "Antmicro" (at 59.055 55.245 0)
      (effects (font (size 1.27 1.27) (thickness 0.15)) (justify left bottom) hide)
    )
    (property "Voltage" "50V" (at 56.515 55.245 0)
      (effects (font (size 1.27 1.27)) (justify left bottom) hide)
    )
    (property "Dielectric" "X7R" (at 53.975 55.245 0)
      (effects (font (size 1.27 1.27)) (justify left bottom) hide)
    )
    (pin "1")
    (pin "2")
    (instances
      (project "data-center-rdimm-ddr4-tester"
        (path ""
          (reference "C135") (unit 1)
        )
      )
    )
  )

  (symbol (lib_id "antmicroCapacitors0402:C_10n_0402") (at 92.71 34.925 270) (unit 1)
    (in_bom yes) (on_board yes) (dnp no)
    (property "Reference" "C138" (at 93.345 35.56 90)
      (effects (font (size 1.524 1.524)) (justify left))
    )
    (property "Value" "C_10n_0402" (at 82.55 55.245 0)
      (effects (font (size 1.27 1.27) (thickness 0.15)) (justify left bottom) hide)
    )
    (property "Footprint" "antmicro-footprints:C_0402_1005Metric" (at 80.01 55.245 0)
      (effects (font (size 1.27 1.27) (thickness 0.15)) (justify left bottom) hide)
    )
    (property "Datasheet" "https://search.murata.co.jp/Ceramy/image/img/A01X/G101/ENG/GRM155R71H103KA88-01.pdf" (at 77.47 55.245 0)
      (effects (font (size 1.27 1.27) (thickness 0.15)) (justify left bottom) hide)
    )
    (property "Manufacturer" "Murata" (at 72.39 55.245 0)
      (effects (font (size 1.27 1.27) (thickness 0.15)) (justify left bottom) hide)
    )
    (property "MPN" "GRM155R71H103KA88D" (at 74.93 55.245 0)
      (effects (font (size 1.27 1.27) (thickness 0.15)) (justify left bottom) hide)
    )
    (property "Val" "10n" (at 93.345 39.37 90)
      (effects (font (size 1.27 1.27) (thickness 0.15)) (justify left))
    )
    (property "License" "Apache-2.0" (at 69.85 55.245 0)
      (effects (font (size 1.27 1.27) (thickness 0.15)) (justify left bottom) hide)
    )
    (property "Author" "Antmicro" (at 67.31 55.245 0)
      (effects (font (size 1.27 1.27) (thickness 0.15)) (justify left bottom) hide)
    )
    (property "Voltage" "50V" (at 64.77 55.245 0)
      (effects (font (size 1.27 1.27)) (justify left bottom) hide)
    )
    (property "Dielectric" "X7R" (at 62.23 55.245 0)
      (effects (font (size 1.27 1.27)) (justify left bottom) hide)
    )
    (pin "1")
    (pin "2")
    (instances
      (project "data-center-rdimm-ddr4-tester"
        (path ""
          (reference "C138") (unit 1)
        )
      )
    )
  )

  (symbol (lib_id "antmicroCapacitors0402:C_4u7_0402") (at 107.315 142.875 270) (unit 1)
    (in_bom yes) (on_board yes) (dnp no)
    (property "Reference" "C137" (at 107.95 143.51 90)
      (effects (font (size 1.524 1.524)) (justify left))
    )
    (property "Value" "C_4u7_0402" (at 97.155 163.195 0)
      (effects (font (size 1.27 1.27) (thickness 0.15)) (justify left bottom) hide)
    )
    (property "Footprint" "antmicro-footprints:C_0402_1005Metric" (at 94.615 163.195 0)
      (effects (font (size 1.27 1.27) (thickness 0.15)) (justify left bottom) hide)
    )
    (property "Datasheet" " " (at 92.075 163.195 0)
      (effects (font (size 1.27 1.27) (thickness 0.15)) (justify left bottom) hide)
    )
    (property "Manufacturer" "Murata" (at 86.995 163.195 0)
      (effects (font (size 1.27 1.27) (thickness 0.15)) (justify left bottom) hide)
    )
    (property "MPN" "GRM155R61A475MEAAD" (at 89.535 163.195 0)
      (effects (font (size 1.27 1.27) (thickness 0.15)) (justify left bottom) hide)
    )
    (property "Val" "4u7" (at 107.95 147.32 90)
      (effects (font (size 1.27 1.27) (thickness 0.15)) (justify left))
    )
    (property "License" "Apache-2.0" (at 84.455 163.195 0)
      (effects (font (size 1.27 1.27) (thickness 0.15)) (justify left bottom) hide)
    )
    (property "Author" "Antmicro" (at 81.915 163.195 0)
      (effects (font (size 1.27 1.27) (thickness 0.15)) (justify left bottom) hide)
    )
    (property "Voltage" "" (at 79.375 163.195 0)
      (effects (font (size 1.27 1.27)) (justify left bottom) hide)
    )
    (property "Dielectric" "" (at 76.835 163.195 0)
      (effects (font (size 1.27 1.27)) (justify left bottom) hide)
    )
    (pin "1")
    (pin "2")
    (instances
      (project "data-center-rdimm-ddr4-tester"
        (path ""
          (reference "C137") (unit 1)
        )
      )
    )
  )

  (symbol (lib_id "antmicroCapacitors0402:C_470n_0402") (at 76.2 34.925 270) (unit 1)
    (in_bom yes) (on_board yes) (dnp no)
    (property "Reference" "C130" (at 76.835 35.56 90)
      (effects (font (size 1.524 1.524)) (justify left))
    )
    (property "Value" "C_470n_0402" (at 66.04 55.245 0)
      (effects (font (size 1.27 1.27) (thickness 0.15)) (justify left bottom) hide)
    )
    (property "Footprint" "antmicro-footprints:C_0402_1005Metric" (at 63.5 55.245 0)
      (effects (font (size 1.27 1.27) (thickness 0.15)) (justify left bottom) hide)
    )
    (property "Datasheet" " " (at 60.96 55.245 0)
      (effects (font (size 1.27 1.27) (thickness 0.15)) (justify left bottom) hide)
    )
    (property "Manufacturer" "TDK" (at 55.88 55.245 0)
      (effects (font (size 1.27 1.27) (thickness 0.15)) (justify left bottom) hide)
    )
    (property "MPN" "C1005X5R1E474M050BB" (at 58.42 55.245 0)
      (effects (font (size 1.27 1.27) (thickness 0.15)) (justify left bottom) hide)
    )
    (property "Val" "470n" (at 76.835 39.37 90)
      (effects (font (size 1.27 1.27) (thickness 0.15)) (justify left))
    )
    (property "License" "Apache-2.0" (at 53.34 55.245 0)
      (effects (font (size 1.27 1.27) (thickness 0.15)) (justify left bottom) hide)
    )
    (property "Author" "Antmicro" (at 50.8 55.245 0)
      (effects (font (size 1.27 1.27) (thickness 0.15)) (justify left bottom) hide)
    )
    (property "Voltage" "" (at 48.26 55.245 0)
      (effects (font (size 1.27 1.27)) (justify left bottom) hide)
    )
    (property "Dielectric" "" (at 45.72 55.245 0)
      (effects (font (size 1.27 1.27)) (justify left bottom) hide)
    )
    (pin "1")
    (pin "2")
    (instances
      (project "data-center-rdimm-ddr4-tester"
        (path ""
          (reference "C130") (unit 1)
        )
      )
    )
  )

  (symbol (lib_id "antmicroCapacitors0402:C_4u7_0402") (at 43.18 34.925 270) (unit 1)
    (in_bom yes) (on_board yes) (dnp no)
    (property "Reference" "C119" (at 43.815 35.56 90)
      (effects (font (size 1.524 1.524)) (justify left))
    )
    (property "Value" "C_4u7_0402" (at 33.02 55.245 0)
      (effects (font (size 1.27 1.27) (thickness 0.15)) (justify left bottom) hide)
    )
    (property "Footprint" "antmicro-footprints:C_0402_1005Metric" (at 30.48 55.245 0)
      (effects (font (size 1.27 1.27) (thickness 0.15)) (justify left bottom) hide)
    )
    (property "Datasheet" " " (at 27.94 55.245 0)
      (effects (font (size 1.27 1.27) (thickness 0.15)) (justify left bottom) hide)
    )
    (property "Manufacturer" "Murata" (at 22.86 55.245 0)
      (effects (font (size 1.27 1.27) (thickness 0.15)) (justify left bottom) hide)
    )
    (property "MPN" "GRM155R61A475MEAAD" (at 25.4 55.245 0)
      (effects (font (size 1.27 1.27) (thickness 0.15)) (justify left bottom) hide)
    )
    (property "Val" "4u7" (at 43.815 39.37 90)
      (effects (font (size 1.27 1.27) (thickness 0.15)) (justify left))
    )
    (property "License" "Apache-2.0" (at 20.32 55.245 0)
      (effects (font (size 1.27 1.27) (thickness 0.15)) (justify left bottom) hide)
    )
    (property "Author" "Antmicro" (at 17.78 55.245 0)
      (effects (font (size 1.27 1.27) (thickness 0.15)) (justify left bottom) hide)
    )
    (property "Voltage" "" (at 15.24 55.245 0)
      (effects (font (size 1.27 1.27)) (justify left bottom) hide)
    )
    (property "Dielectric" "" (at 12.7 55.245 0)
      (effects (font (size 1.27 1.27)) (justify left bottom) hide)
    )
    (pin "1")
    (pin "2")
    (instances
      (project "data-center-rdimm-ddr4-tester"
        (path ""
          (reference "C119") (unit 1)
        )
      )
    )
  )

  (symbol (lib_id "antmicroCapacitors0402:C_470n_0402") (at 51.435 34.925 270) (unit 1)
    (in_bom yes) (on_board yes) (dnp no)
    (property "Reference" "C120" (at 52.07 35.56 90)
      (effects (font (size 1.524 1.524)) (justify left))
    )
    (property "Value" "C_470n_0402" (at 41.275 55.245 0)
      (effects (font (size 1.27 1.27) (thickness 0.15)) (justify left bottom) hide)
    )
    (property "Footprint" "antmicro-footprints:C_0402_1005Metric" (at 38.735 55.245 0)
      (effects (font (size 1.27 1.27) (thickness 0.15)) (justify left bottom) hide)
    )
    (property "Datasheet" " " (at 36.195 55.245 0)
      (effects (font (size 1.27 1.27) (thickness 0.15)) (justify left bottom) hide)
    )
    (property "Manufacturer" "TDK" (at 31.115 55.245 0)
      (effects (font (size 1.27 1.27) (thickness 0.15)) (justify left bottom) hide)
    )
    (property "MPN" "C1005X5R1E474M050BB" (at 33.655 55.245 0)
      (effects (font (size 1.27 1.27) (thickness 0.15)) (justify left bottom) hide)
    )
    (property "Val" "470n" (at 52.07 39.37 90)
      (effects (font (size 1.27 1.27) (thickness 0.15)) (justify left))
    )
    (property "License" "Apache-2.0" (at 28.575 55.245 0)
      (effects (font (size 1.27 1.27) (thickness 0.15)) (justify left bottom) hide)
    )
    (property "Author" "Antmicro" (at 26.035 55.245 0)
      (effects (font (size 1.27 1.27) (thickness 0.15)) (justify left bottom) hide)
    )
    (property "Voltage" "" (at 23.495 55.245 0)
      (effects (font (size 1.27 1.27)) (justify left bottom) hide)
    )
    (property "Dielectric" "" (at 20.955 55.245 0)
      (effects (font (size 1.27 1.27)) (justify left bottom) hide)
    )
    (pin "1")
    (pin "2")
    (instances
      (project "data-center-rdimm-ddr4-tester"
        (path ""
          (reference "C120") (unit 1)
        )
      )
    )
  )

  (symbol (lib_id "antmicroCapacitors0402:C_470n_0402") (at 59.69 34.925 270) (unit 1)
    (in_bom yes) (on_board yes) (dnp no)
    (property "Reference" "C122" (at 60.325 35.56 90)
      (effects (font (size 1.524 1.524)) (justify left))
    )
    (property "Value" "C_470n_0402" (at 49.53 55.245 0)
      (effects (font (size 1.27 1.27) (thickness 0.15)) (justify left bottom) hide)
    )
    (property "Footprint" "antmicro-footprints:C_0402_1005Metric" (at 46.99 55.245 0)
      (effects (font (size 1.27 1.27) (thickness 0.15)) (justify left bottom) hide)
    )
    (property "Datasheet" " " (at 44.45 55.245 0)
      (effects (font (size 1.27 1.27) (thickness 0.15)) (justify left bottom) hide)
    )
    (property "Manufacturer" "TDK" (at 39.37 55.245 0)
      (effects (font (size 1.27 1.27) (thickness 0.15)) (justify left bottom) hide)
    )
    (property "MPN" "C1005X5R1E474M050BB" (at 41.91 55.245 0)
      (effects (font (size 1.27 1.27) (thickness 0.15)) (justify left bottom) hide)
    )
    (property "Val" "470n" (at 60.325 39.37 90)
      (effects (font (size 1.27 1.27) (thickness 0.15)) (justify left))
    )
    (property "License" "Apache-2.0" (at 36.83 55.245 0)
      (effects (font (size 1.27 1.27) (thickness 0.15)) (justify left bottom) hide)
    )
    (property "Author" "Antmicro" (at 34.29 55.245 0)
      (effects (font (size 1.27 1.27) (thickness 0.15)) (justify left bottom) hide)
    )
    (property "Voltage" "" (at 31.75 55.245 0)
      (effects (font (size 1.27 1.27)) (justify left bottom) hide)
    )
    (property "Dielectric" "" (at 29.21 55.245 0)
      (effects (font (size 1.27 1.27)) (justify left bottom) hide)
    )
    (pin "1")
    (pin "2")
    (instances
      (project "data-center-rdimm-ddr4-tester"
        (path ""
          (reference "C122") (unit 1)
        )
      )
    )
  )

  (symbol (lib_id "antmicroCapacitors0402:C_470n_0402") (at 67.945 34.925 270) (unit 1)
    (in_bom yes) (on_board yes) (dnp no)
    (property "Reference" "C126" (at 68.58 35.56 90)
      (effects (font (size 1.524 1.524)) (justify left))
    )
    (property "Value" "C_470n_0402" (at 57.785 55.245 0)
      (effects (font (size 1.27 1.27) (thickness 0.15)) (justify left bottom) hide)
    )
    (property "Footprint" "antmicro-footprints:C_0402_1005Metric" (at 55.245 55.245 0)
      (effects (font (size 1.27 1.27) (thickness 0.15)) (justify left bottom) hide)
    )
    (property "Datasheet" " " (at 52.705 55.245 0)
      (effects (font (size 1.27 1.27) (thickness 0.15)) (justify left bottom) hide)
    )
    (property "Manufacturer" "TDK" (at 47.625 55.245 0)
      (effects (font (size 1.27 1.27) (thickness 0.15)) (justify left bottom) hide)
    )
    (property "MPN" "C1005X5R1E474M050BB" (at 50.165 55.245 0)
      (effects (font (size 1.27 1.27) (thickness 0.15)) (justify left bottom) hide)
    )
    (property "Val" "470n" (at 68.58 39.37 90)
      (effects (font (size 1.27 1.27) (thickness 0.15)) (justify left))
    )
    (property "License" "Apache-2.0" (at 45.085 55.245 0)
      (effects (font (size 1.27 1.27) (thickness 0.15)) (justify left bottom) hide)
    )
    (property "Author" "Antmicro" (at 42.545 55.245 0)
      (effects (font (size 1.27 1.27) (thickness 0.15)) (justify left bottom) hide)
    )
    (property "Voltage" "" (at 40.005 55.245 0)
      (effects (font (size 1.27 1.27)) (justify left bottom) hide)
    )
    (property "Dielectric" "" (at 37.465 55.245 0)
      (effects (font (size 1.27 1.27)) (justify left bottom) hide)
    )
    (pin "1")
    (pin "2")
    (instances
      (project "data-center-rdimm-ddr4-tester"
        (path ""
          (reference "C126") (unit 1)
        )
      )
    )
  )

  (symbol (lib_id "antmicroCapacitors0402:C_4u7_0402") (at 115.57 142.875 270) (unit 1)
    (in_bom yes) (on_board yes) (dnp no)
    (property "Reference" "C140" (at 116.205 143.51 90)
      (effects (font (size 1.524 1.524)) (justify left))
    )
    (property "Value" "C_4u7_0402" (at 105.41 163.195 0)
      (effects (font (size 1.27 1.27) (thickness 0.15)) (justify left bottom) hide)
    )
    (property "Footprint" "antmicro-footprints:C_0402_1005Metric" (at 102.87 163.195 0)
      (effects (font (size 1.27 1.27) (thickness 0.15)) (justify left bottom) hide)
    )
    (property "Datasheet" " " (at 100.33 163.195 0)
      (effects (font (size 1.27 1.27) (thickness 0.15)) (justify left bottom) hide)
    )
    (property "Manufacturer" "Murata" (at 95.25 163.195 0)
      (effects (font (size 1.27 1.27) (thickness 0.15)) (justify left bottom) hide)
    )
    (property "MPN" "GRM155R61A475MEAAD" (at 97.79 163.195 0)
      (effects (font (size 1.27 1.27) (thickness 0.15)) (justify left bottom) hide)
    )
    (property "Val" "4u7" (at 116.205 147.32 90)
      (effects (font (size 1.27 1.27) (thickness 0.15)) (justify left))
    )
    (property "License" "Apache-2.0" (at 92.71 163.195 0)
      (effects (font (size 1.27 1.27) (thickness 0.15)) (justify left bottom) hide)
    )
    (property "Author" "Antmicro" (at 90.17 163.195 0)
      (effects (font (size 1.27 1.27) (thickness 0.15)) (justify left bottom) hide)
    )
    (property "Voltage" "" (at 87.63 163.195 0)
      (effects (font (size 1.27 1.27)) (justify left bottom) hide)
    )
    (property "Dielectric" "" (at 85.09 163.195 0)
      (effects (font (size 1.27 1.27)) (justify left bottom) hide)
    )
    (pin "1")
    (pin "2")
    (instances
      (project "data-center-rdimm-ddr4-tester"
        (path ""
          (reference "C140") (unit 1)
        )
      )
    )
  )

  (symbol (lib_id "antmicroCapacitors0402:C_4u7_0402") (at 99.06 142.875 270) (unit 1)
    (in_bom yes) (on_board yes) (dnp no)
    (property "Reference" "C132" (at 99.695 143.51 90)
      (effects (font (size 1.524 1.524)) (justify left))
    )
    (property "Value" "C_4u7_0402" (at 88.9 163.195 0)
      (effects (font (size 1.27 1.27) (thickness 0.15)) (justify left bottom) hide)
    )
    (property "Footprint" "antmicro-footprints:C_0402_1005Metric" (at 86.36 163.195 0)
      (effects (font (size 1.27 1.27) (thickness 0.15)) (justify left bottom) hide)
    )
    (property "Datasheet" " " (at 83.82 163.195 0)
      (effects (font (size 1.27 1.27) (thickness 0.15)) (justify left bottom) hide)
    )
    (property "Manufacturer" "Murata" (at 78.74 163.195 0)
      (effects (font (size 1.27 1.27) (thickness 0.15)) (justify left bottom) hide)
    )
    (property "MPN" "GRM155R61A475MEAAD" (at 81.28 163.195 0)
      (effects (font (size 1.27 1.27) (thickness 0.15)) (justify left bottom) hide)
    )
    (property "Val" "4u7" (at 99.695 147.32 90)
      (effects (font (size 1.27 1.27) (thickness 0.15)) (justify left))
    )
    (property "License" "Apache-2.0" (at 76.2 163.195 0)
      (effects (font (size 1.27 1.27) (thickness 0.15)) (justify left bottom) hide)
    )
    (property "Author" "Antmicro" (at 73.66 163.195 0)
      (effects (font (size 1.27 1.27) (thickness 0.15)) (justify left bottom) hide)
    )
    (property "Voltage" "" (at 71.12 163.195 0)
      (effects (font (size 1.27 1.27)) (justify left bottom) hide)
    )
    (property "Dielectric" "" (at 68.58 163.195 0)
      (effects (font (size 1.27 1.27)) (justify left bottom) hide)
    )
    (pin "1")
    (pin "2")
    (instances
      (project "data-center-rdimm-ddr4-tester"
        (path ""
          (reference "C132") (unit 1)
        )
      )
    )
  )

  (symbol (lib_id "antmicroCapacitors0402:C_4u7_0402") (at 29.845 91.44 270) (unit 1)
    (in_bom yes) (on_board yes) (dnp no)
    (property "Reference" "C123" (at 30.48 92.075 90)
      (effects (font (size 1.524 1.524)) (justify left))
    )
    (property "Value" "C_4u7_0402" (at 19.685 111.76 0)
      (effects (font (size 1.27 1.27) (thickness 0.15)) (justify left bottom) hide)
    )
    (property "Footprint" "antmicro-footprints:C_0402_1005Metric" (at 17.145 111.76 0)
      (effects (font (size 1.27 1.27) (thickness 0.15)) (justify left bottom) hide)
    )
    (property "Datasheet" " " (at 14.605 111.76 0)
      (effects (font (size 1.27 1.27) (thickness 0.15)) (justify left bottom) hide)
    )
    (property "Manufacturer" "Murata" (at 9.525 111.76 0)
      (effects (font (size 1.27 1.27) (thickness 0.15)) (justify left bottom) hide)
    )
    (property "MPN" "GRM155R61A475MEAAD" (at 12.065 111.76 0)
      (effects (font (size 1.27 1.27) (thickness 0.15)) (justify left bottom) hide)
    )
    (property "Val" "4u7" (at 30.48 95.885 90)
      (effects (font (size 1.27 1.27) (thickness 0.15)) (justify left))
    )
    (property "License" "Apache-2.0" (at 6.985 111.76 0)
      (effects (font (size 1.27 1.27) (thickness 0.15)) (justify left bottom) hide)
    )
    (property "Author" "Antmicro" (at 4.445 111.76 0)
      (effects (font (size 1.27 1.27) (thickness 0.15)) (justify left bottom) hide)
    )
    (property "Voltage" "" (at 1.905 111.76 0)
      (effects (font (size 1.27 1.27)) (justify left bottom) hide)
    )
    (property "Dielectric" "" (at -0.635 111.76 0)
      (effects (font (size 1.27 1.27)) (justify left bottom) hide)
    )
    (pin "1")
    (pin "2")
    (instances
      (project "data-center-rdimm-ddr4-tester"
        (path ""
          (reference "C123") (unit 1)
        )
      )
    )
  )

  (symbol (lib_id "antmicroCapacitors0402:C_470n_0402") (at 38.1 91.44 270) (unit 1)
    (in_bom yes) (on_board yes) (dnp no)
    (property "Reference" "C127" (at 38.735 92.075 90)
      (effects (font (size 1.524 1.524)) (justify left))
    )
    (property "Value" "C_470n_0402" (at 27.94 111.76 0)
      (effects (font (size 1.27 1.27) (thickness 0.15)) (justify left bottom) hide)
    )
    (property "Footprint" "antmicro-footprints:C_0402_1005Metric" (at 25.4 111.76 0)
      (effects (font (size 1.27 1.27) (thickness 0.15)) (justify left bottom) hide)
    )
    (property "Datasheet" " " (at 22.86 111.76 0)
      (effects (font (size 1.27 1.27) (thickness 0.15)) (justify left bottom) hide)
    )
    (property "Manufacturer" "TDK" (at 17.78 111.76 0)
      (effects (font (size 1.27 1.27) (thickness 0.15)) (justify left bottom) hide)
    )
    (property "MPN" "C1005X5R1E474M050BB" (at 20.32 111.76 0)
      (effects (font (size 1.27 1.27) (thickness 0.15)) (justify left bottom) hide)
    )
    (property "Val" "470n" (at 38.735 95.885 90)
      (effects (font (size 1.27 1.27) (thickness 0.15)) (justify left))
    )
    (property "License" "Apache-2.0" (at 15.24 111.76 0)
      (effects (font (size 1.27 1.27) (thickness 0.15)) (justify left bottom) hide)
    )
    (property "Author" "Antmicro" (at 12.7 111.76 0)
      (effects (font (size 1.27 1.27) (thickness 0.15)) (justify left bottom) hide)
    )
    (property "Voltage" "" (at 10.16 111.76 0)
      (effects (font (size 1.27 1.27)) (justify left bottom) hide)
    )
    (property "Dielectric" "" (at 7.62 111.76 0)
      (effects (font (size 1.27 1.27)) (justify left bottom) hide)
    )
    (pin "1")
    (pin "2")
    (instances
      (project "data-center-rdimm-ddr4-tester"
        (path ""
          (reference "C127") (unit 1)
        )
      )
    )
  )

  (symbol (lib_id "antmicroCapacitors0402:C_10n_0402") (at 54.61 91.44 270) (unit 1)
    (in_bom yes) (on_board yes) (dnp no)
    (property "Reference" "C136" (at 55.245 92.075 90)
      (effects (font (size 1.524 1.524)) (justify left))
    )
    (property "Value" "C_10n_0402" (at 44.45 111.76 0)
      (effects (font (size 1.27 1.27) (thickness 0.15)) (justify left bottom) hide)
    )
    (property "Footprint" "antmicro-footprints:C_0402_1005Metric" (at 41.91 111.76 0)
      (effects (font (size 1.27 1.27) (thickness 0.15)) (justify left bottom) hide)
    )
    (property "Datasheet" "https://search.murata.co.jp/Ceramy/image/img/A01X/G101/ENG/GRM155R71H103KA88-01.pdf" (at 39.37 111.76 0)
      (effects (font (size 1.27 1.27) (thickness 0.15)) (justify left bottom) hide)
    )
    (property "Manufacturer" "Murata" (at 34.29 111.76 0)
      (effects (font (size 1.27 1.27) (thickness 0.15)) (justify left bottom) hide)
    )
    (property "MPN" "GRM155R71H103KA88D" (at 36.83 111.76 0)
      (effects (font (size 1.27 1.27) (thickness 0.15)) (justify left bottom) hide)
    )
    (property "Val" "10n" (at 55.245 95.885 90)
      (effects (font (size 1.27 1.27) (thickness 0.15)) (justify left))
    )
    (property "License" "Apache-2.0" (at 31.75 111.76 0)
      (effects (font (size 1.27 1.27) (thickness 0.15)) (justify left bottom) hide)
    )
    (property "Author" "Antmicro" (at 29.21 111.76 0)
      (effects (font (size 1.27 1.27) (thickness 0.15)) (justify left bottom) hide)
    )
    (property "Voltage" "50V" (at 26.67 111.76 0)
      (effects (font (size 1.27 1.27)) (justify left bottom) hide)
    )
    (property "Dielectric" "X7R" (at 24.13 111.76 0)
      (effects (font (size 1.27 1.27)) (justify left bottom) hide)
    )
    (pin "1")
    (pin "2")
    (instances
      (project "data-center-rdimm-ddr4-tester"
        (path ""
          (reference "C136") (unit 1)
        )
      )
    )
  )

  (symbol (lib_id "antmicroCapacitors0402:C_10n_0402") (at 62.865 91.44 270) (unit 1)
    (in_bom yes) (on_board yes) (dnp no)
    (property "Reference" "C139" (at 63.5 92.075 90)
      (effects (font (size 1.524 1.524)) (justify left))
    )
    (property "Value" "C_10n_0402" (at 52.705 111.76 0)
      (effects (font (size 1.27 1.27) (thickness 0.15)) (justify left bottom) hide)
    )
    (property "Footprint" "antmicro-footprints:C_0402_1005Metric" (at 50.165 111.76 0)
      (effects (font (size 1.27 1.27) (thickness 0.15)) (justify left bottom) hide)
    )
    (property "Datasheet" "https://search.murata.co.jp/Ceramy/image/img/A01X/G101/ENG/GRM155R71H103KA88-01.pdf" (at 47.625 111.76 0)
      (effects (font (size 1.27 1.27) (thickness 0.15)) (justify left bottom) hide)
    )
    (property "Manufacturer" "Murata" (at 42.545 111.76 0)
      (effects (font (size 1.27 1.27) (thickness 0.15)) (justify left bottom) hide)
    )
    (property "MPN" "GRM155R71H103KA88D" (at 45.085 111.76 0)
      (effects (font (size 1.27 1.27) (thickness 0.15)) (justify left bottom) hide)
    )
    (property "Val" "10n" (at 63.5 95.885 90)
      (effects (font (size 1.27 1.27) (thickness 0.15)) (justify left))
    )
    (property "License" "Apache-2.0" (at 40.005 111.76 0)
      (effects (font (size 1.27 1.27) (thickness 0.15)) (justify left bottom) hide)
    )
    (property "Author" "Antmicro" (at 37.465 111.76 0)
      (effects (font (size 1.27 1.27) (thickness 0.15)) (justify left bottom) hide)
    )
    (property "Voltage" "50V" (at 34.925 111.76 0)
      (effects (font (size 1.27 1.27)) (justify left bottom) hide)
    )
    (property "Dielectric" "X7R" (at 32.385 111.76 0)
      (effects (font (size 1.27 1.27)) (justify left bottom) hide)
    )
    (pin "1")
    (pin "2")
    (instances
      (project "data-center-rdimm-ddr4-tester"
        (path ""
          (reference "C139") (unit 1)
        )
      )
    )
  )

  (symbol (lib_id "antmicroCapacitors0402:C_10n_0402") (at 46.355 91.44 270) (unit 1)
    (in_bom yes) (on_board yes) (dnp no)
    (property "Reference" "C131" (at 46.99 92.075 90)
      (effects (font (size 1.524 1.524)) (justify left))
    )
    (property "Value" "C_10n_0402" (at 36.195 111.76 0)
      (effects (font (size 1.27 1.27) (thickness 0.15)) (justify left bottom) hide)
    )
    (property "Footprint" "antmicro-footprints:C_0402_1005Metric" (at 33.655 111.76 0)
      (effects (font (size 1.27 1.27) (thickness 0.15)) (justify left bottom) hide)
    )
    (property "Datasheet" "https://search.murata.co.jp/Ceramy/image/img/A01X/G101/ENG/GRM155R71H103KA88-01.pdf" (at 31.115 111.76 0)
      (effects (font (size 1.27 1.27) (thickness 0.15)) (justify left bottom) hide)
    )
    (property "Manufacturer" "Murata" (at 26.035 111.76 0)
      (effects (font (size 1.27 1.27) (thickness 0.15)) (justify left bottom) hide)
    )
    (property "MPN" "GRM155R71H103KA88D" (at 28.575 111.76 0)
      (effects (font (size 1.27 1.27) (thickness 0.15)) (justify left bottom) hide)
    )
    (property "Val" "10n" (at 46.99 95.885 90)
      (effects (font (size 1.27 1.27) (thickness 0.15)) (justify left))
    )
    (property "License" "Apache-2.0" (at 23.495 111.76 0)
      (effects (font (size 1.27 1.27) (thickness 0.15)) (justify left bottom) hide)
    )
    (property "Author" "Antmicro" (at 20.955 111.76 0)
      (effects (font (size 1.27 1.27) (thickness 0.15)) (justify left bottom) hide)
    )
    (property "Voltage" "50V" (at 18.415 111.76 0)
      (effects (font (size 1.27 1.27)) (justify left bottom) hide)
    )
    (property "Dielectric" "X7R" (at 15.875 111.76 0)
      (effects (font (size 1.27 1.27)) (justify left bottom) hide)
    )
    (pin "1")
    (pin "2")
    (instances
      (project "data-center-rdimm-ddr4-tester"
        (path ""
          (reference "C131") (unit 1)
        )
      )
    )
  )

  (symbol (lib_id "data-center-rdimm-ddr4-tester:FB_120Z_2A_0603") (at 31.115 140.97 0) (mirror y) (unit 1)
    (in_bom yes) (on_board yes) (dnp no)
    (property "Reference" "FB3" (at 28.575 134.62 0)
      (effects (font (size 1.524 1.524)))
    )
    (property "Value" "FB_120Z_2A_0603" (at 15.875 146.05 0)
      (effects (font (size 1.27 1.27) (thickness 0.15)) (justify left bottom) hide)
    )
    (property "Footprint" "data-center-rdimm-ddr4-tester-footprints:FB_0603_1608Metric" (at 15.875 148.59 0)
      (effects (font (size 1.27 1.27) (thickness 0.15)) (justify left bottom) hide)
    )
    (property "Datasheet" "https://www.murata.com/en-us/products/productdata/8796738650142/ENFA0003.pdf" (at 15.875 151.13 0)
      (effects (font (size 1.27 1.27) (thickness 0.15)) (justify left bottom) hide)
    )
    (property "MPN" "BLM18PG121SN1D" (at 28.6131 137.16 0)
      (effects (font (size 1.27 1.27) (thickness 0.15)))
    )
    (property "Manufacturer" "Murata" (at 15.875 156.21 0)
      (effects (font (size 1.27 1.27) (thickness 0.15)) (justify left bottom) hide)
    )
    (property "Author" "Antmicro" (at 15.875 158.75 0)
      (effects (font (size 1.27 1.27) (thickness 0.15)) (justify left bottom) hide)
    )
    (property "License" "Apache-2.0" (at 15.875 161.29 0)
      (effects (font (size 1.27 1.27) (thickness 0.15)) (justify left bottom) hide)
    )
    (pin "1")
    (pin "2")
    (instances
      (project "data-center-rdimm-ddr4-tester"
        (path ""
          (reference "FB3") (unit 1)
        )
      )
    )
  )

  (symbol (lib_id "data-center-rdimm-ddr4-tester:FB_120Z_2A_0603") (at 92.71 140.335 0) (unit 1)
    (in_bom yes) (on_board yes) (dnp no)
    (property "Reference" "FB1" (at 95.2881 134.62 0)
      (effects (font (size 1.524 1.524)))
    )
    (property "Value" "FB_120Z_2A_0603" (at 107.95 145.415 0)
      (effects (font (size 1.27 1.27) (thickness 0.15)) (justify left bottom) hide)
    )
    (property "Footprint" "data-center-rdimm-ddr4-tester-footprints:FB_0603_1608Metric" (at 107.95 147.955 0)
      (effects (font (size 1.27 1.27) (thickness 0.15)) (justify left bottom) hide)
    )
    (property "Datasheet" "https://www.murata.com/en-us/products/productdata/8796738650142/ENFA0003.pdf" (at 107.95 150.495 0)
      (effects (font (size 1.27 1.27) (thickness 0.15)) (justify left bottom) hide)
    )
    (property "MPN" "BLM18PG121SN1D" (at 95.25 137.16 0)
      (effects (font (size 1.27 1.27) (thickness 0.15)))
    )
    (property "Manufacturer" "Murata" (at 107.95 155.575 0)
      (effects (font (size 1.27 1.27) (thickness 0.15)) (justify left bottom) hide)
    )
    (property "Author" "Antmicro" (at 107.95 158.115 0)
      (effects (font (size 1.27 1.27) (thickness 0.15)) (justify left bottom) hide)
    )
    (property "License" "Apache-2.0" (at 107.95 160.655 0)
      (effects (font (size 1.27 1.27) (thickness 0.15)) (justify left bottom) hide)
    )
    (pin "1")
    (pin "2")
    (instances
      (project "data-center-rdimm-ddr4-tester"
        (path ""
          (reference "FB1") (unit 1)
        )
      )
    )
  )

  (symbol (lib_id "data-center-rdimm-ddr4-tester:FB_120Z_2A_0603") (at 99.06 88.9 0) (mirror y) (unit 1)
    (in_bom yes) (on_board yes) (dnp no)
    (property "Reference" "FB2" (at 96.52 82.55 0)
      (effects (font (size 1.524 1.524)))
    )
    (property "Value" "FB_120Z_2A_0603" (at 83.82 93.98 0)
      (effects (font (size 1.27 1.27) (thickness 0.15)) (justify left bottom) hide)
    )
    (property "Footprint" "data-center-rdimm-ddr4-tester-footprints:FB_0603_1608Metric" (at 83.82 96.52 0)
      (effects (font (size 1.27 1.27) (thickness 0.15)) (justify left bottom) hide)
    )
    (property "Datasheet" "https://www.murata.com/en-us/products/productdata/8796738650142/ENFA0003.pdf" (at 83.82 99.06 0)
      (effects (font (size 1.27 1.27) (thickness 0.15)) (justify left bottom) hide)
    )
    (property "MPN" "BLM18PG121SN1D" (at 96.5581 85.09 0)
      (effects (font (size 1.27 1.27) (thickness 0.15)))
    )
    (property "Manufacturer" "Murata" (at 83.82 104.14 0)
      (effects (font (size 1.27 1.27) (thickness 0.15)) (justify left bottom) hide)
    )
    (property "Author" "Antmicro" (at 83.82 106.68 0)
      (effects (font (size 1.27 1.27) (thickness 0.15)) (justify left bottom) hide)
    )
    (property "License" "Apache-2.0" (at 83.82 109.22 0)
      (effects (font (size 1.27 1.27) (thickness 0.15)) (justify left bottom) hide)
    )
    (pin "1")
    (pin "2")
    (instances
      (project "data-center-rdimm-ddr4-tester"
        (path ""
          (reference "FB2") (unit 1)
        )
      )
    )
  )

  (symbol (lib_id "data-center-rdimm-ddr4-tester:C_100n_16V_0402") (at 111.76 95.885 270) (mirror x) (unit 1)
    (in_bom yes) (on_board yes) (dnp no)
    (property "Reference" "C128" (at 112.395 91.44 90)
      (effects (font (size 1.524 1.524)) (justify left))
    )
    (property "Value" "C_100n_16V_0402" (at 101.6 75.565 0)
      (effects (font (size 1.27 1.27) (thickness 0.15)) (justify left bottom) hide)
    )
    (property "Footprint" "data-center-rdimm-ddr4-tester-footprints:C_0402_1005Metric" (at 99.06 75.565 0)
      (effects (font (size 1.27 1.27) (thickness 0.15)) (justify left bottom) hide)
    )
    (property "Datasheet" " " (at 96.52 75.565 0)
      (effects (font (size 1.27 1.27) (thickness 0.15)) (justify left bottom) hide)
    )
    (property "Manufacturer" "Multicomp" (at 91.44 75.565 0)
      (effects (font (size 1.27 1.27) (thickness 0.15)) (justify left bottom) hide)
    )
    (property "MPN" "MC0402B104K160CT" (at 93.98 75.565 0)
      (effects (font (size 1.27 1.27) (thickness 0.15)) (justify left bottom) hide)
    )
    (property "Val" "100n" (at 112.395 95.25 90)
      (effects (font (size 1.27 1.27) (thickness 0.15)) (justify left))
    )
    (property "License" "Apache-2.0" (at 88.9 75.565 0)
      (effects (font (size 1.27 1.27) (thickness 0.15)) (justify left bottom) hide)
    )
    (property "Author" "Antmicro" (at 86.36 75.565 0)
      (effects (font (size 1.27 1.27) (thickness 0.15)) (justify left bottom) hide)
    )
    (property "Voltage" "" (at 83.82 75.565 0)
      (effects (font (size 1.27 1.27)) (justify left bottom) hide)
    )
    (property "Dielectric" "" (at 81.28 75.565 0)
      (effects (font (size 1.27 1.27)) (justify left bottom) hide)
    )
    (pin "1")
    (pin "2")
    (instances
      (project "data-center-rdimm-ddr4-tester"
        (path ""
          (reference "C128") (unit 1)
        )
      )
    )
  )

  (symbol (lib_id "antmicroCapacitors0402:C_4u7_0402") (at 120.015 95.885 270) (mirror x) (unit 1)
    (in_bom yes) (on_board yes) (dnp no)
    (property "Reference" "C124" (at 120.65 91.44 90)
      (effects (font (size 1.524 1.524)) (justify left))
    )
    (property "Value" "C_4u7_0402" (at 109.855 75.565 0)
      (effects (font (size 1.27 1.27) (thickness 0.15)) (justify left bottom) hide)
    )
    (property "Footprint" "antmicro-footprints:C_0402_1005Metric" (at 107.315 75.565 0)
      (effects (font (size 1.27 1.27) (thickness 0.15)) (justify left bottom) hide)
    )
    (property "Datasheet" " " (at 104.775 75.565 0)
      (effects (font (size 1.27 1.27) (thickness 0.15)) (justify left bottom) hide)
    )
    (property "Manufacturer" "Murata" (at 99.695 75.565 0)
      (effects (font (size 1.27 1.27) (thickness 0.15)) (justify left bottom) hide)
    )
    (property "MPN" "GRM155R61A475MEAAD" (at 102.235 75.565 0)
      (effects (font (size 1.27 1.27) (thickness 0.15)) (justify left bottom) hide)
    )
    (property "Val" "4u7" (at 120.65 95.25 90)
      (effects (font (size 1.27 1.27) (thickness 0.15)) (justify left))
    )
    (property "License" "Apache-2.0" (at 97.155 75.565 0)
      (effects (font (size 1.27 1.27) (thickness 0.15)) (justify left bottom) hide)
    )
    (property "Author" "Antmicro" (at 94.615 75.565 0)
      (effects (font (size 1.27 1.27) (thickness 0.15)) (justify left bottom) hide)
    )
    (property "Voltage" "" (at 92.075 75.565 0)
      (effects (font (size 1.27 1.27)) (justify left bottom) hide)
    )
    (property "Dielectric" "" (at 89.535 75.565 0)
      (effects (font (size 1.27 1.27)) (justify left bottom) hide)
    )
    (pin "1")
    (pin "2")
    (instances
      (project "data-center-rdimm-ddr4-tester"
        (path ""
          (reference "C124") (unit 1)
        )
      )
    )
  )

  (symbol (lib_id "antmicroCapacitors0402:C_10n_0402") (at 103.505 95.885 270) (mirror x) (unit 1)
    (in_bom yes) (on_board yes) (dnp no)
    (property "Reference" "C133" (at 104.14 91.44 90)
      (effects (font (size 1.524 1.524)) (justify left))
    )
    (property "Value" "C_10n_0402" (at 93.345 75.565 0)
      (effects (font (size 1.27 1.27) (thickness 0.15)) (justify left bottom) hide)
    )
    (property "Footprint" "antmicro-footprints:C_0402_1005Metric" (at 90.805 75.565 0)
      (effects (font (size 1.27 1.27) (thickness 0.15)) (justify left bottom) hide)
    )
    (property "Datasheet" "https://search.murata.co.jp/Ceramy/image/img/A01X/G101/ENG/GRM155R71H103KA88-01.pdf" (at 88.265 75.565 0)
      (effects (font (size 1.27 1.27) (thickness 0.15)) (justify left bottom) hide)
    )
    (property "Manufacturer" "Murata" (at 83.185 75.565 0)
      (effects (font (size 1.27 1.27) (thickness 0.15)) (justify left bottom) hide)
    )
    (property "MPN" "GRM155R71H103KA88D" (at 85.725 75.565 0)
      (effects (font (size 1.27 1.27) (thickness 0.15)) (justify left bottom) hide)
    )
    (property "Val" "10n" (at 104.14 95.25 90)
      (effects (font (size 1.27 1.27) (thickness 0.15)) (justify left))
    )
    (property "License" "Apache-2.0" (at 80.645 75.565 0)
      (effects (font (size 1.27 1.27) (thickness 0.15)) (justify left bottom) hide)
    )
    (property "Author" "Antmicro" (at 78.105 75.565 0)
      (effects (font (size 1.27 1.27) (thickness 0.15)) (justify left bottom) hide)
    )
    (property "Voltage" "50V" (at 75.565 75.565 0)
      (effects (font (size 1.27 1.27)) (justify left bottom) hide)
    )
    (property "Dielectric" "X7R" (at 73.025 75.565 0)
      (effects (font (size 1.27 1.27)) (justify left bottom) hide)
    )
    (pin "1")
    (pin "2")
    (instances
      (project "data-center-rdimm-ddr4-tester"
        (path ""
          (reference "C133") (unit 1)
        )
      )
    )
  )

  (symbol (lib_id "antmicropower:GND") (at 43.18 42.545 0) (unit 1)
    (in_bom yes) (on_board yes) (dnp no) (fields_autoplaced)
    (property "Reference" "#PWR037" (at 43.18 48.895 0)
      (effects (font (size 1.27 1.27)) hide)
    )
    (property "Value" "GND" (at 43.18 46.99 0)
      (effects (font (size 1.27 1.27)))
    )
    (property "Footprint" "" (at 43.18 42.545 0)
      (effects (font (size 1.27 1.27)) hide)
    )
    (property "Datasheet" "" (at 43.18 42.545 0)
      (effects (font (size 1.27 1.27)) hide)
    )
    (property "Author" "Antmicro" (at 52.07 50.165 0)
      (effects (font (size 1.27 1.27) (thickness 0.15)) (justify left bottom) hide)
    )
    (property "License" "Apache-2.0" (at 52.07 52.705 0)
      (effects (font (size 1.27 1.27) (thickness 0.15)) (justify left bottom) hide)
    )
    (pin "1")
    (instances
      (project "data-center-rdimm-ddr4-tester"
        (path ""
          (reference "#PWR037") (unit 1)
        )
      )
    )
  )

  (symbol (lib_id "antmicropower:GND") (at 99.06 150.495 0) (unit 1)
    (in_bom yes) (on_board yes) (dnp no) (fields_autoplaced)
    (property "Reference" "#PWR039" (at 99.06 156.845 0)
      (effects (font (size 1.27 1.27)) hide)
    )
    (property "Value" "GND" (at 99.06 155.575 0)
      (effects (font (size 1.27 1.27)))
    )
    (property "Footprint" "" (at 99.06 150.495 0)
      (effects (font (size 1.27 1.27)) hide)
    )
    (property "Datasheet" "" (at 99.06 150.495 0)
      (effects (font (size 1.27 1.27)) hide)
    )
    (property "Author" "Antmicro" (at 107.95 158.115 0)
      (effects (font (size 1.27 1.27) (thickness 0.15)) (justify left bottom) hide)
    )
    (property "License" "Apache-2.0" (at 107.95 160.655 0)
      (effects (font (size 1.27 1.27) (thickness 0.15)) (justify left bottom) hide)
    )
    (pin "1")
    (instances
      (project "data-center-rdimm-ddr4-tester"
        (path ""
          (reference "#PWR039") (unit 1)
        )
      )
    )
  )

  (symbol (lib_id "antmicropower:GND") (at 29.845 100.33 0) (unit 1)
    (in_bom yes) (on_board yes) (dnp no) (fields_autoplaced)
    (property "Reference" "#PWR038" (at 29.845 106.68 0)
      (effects (font (size 1.27 1.27)) hide)
    )
    (property "Value" "GND" (at 29.845 105.41 0)
      (effects (font (size 1.27 1.27)))
    )
    (property "Footprint" "" (at 29.845 100.33 0)
      (effects (font (size 1.27 1.27)) hide)
    )
    (property "Datasheet" "" (at 29.845 100.33 0)
      (effects (font (size 1.27 1.27)) hide)
    )
    (property "Author" "Antmicro" (at 38.735 107.95 0)
      (effects (font (size 1.27 1.27) (thickness 0.15)) (justify left bottom) hide)
    )
    (property "License" "Apache-2.0" (at 38.735 110.49 0)
      (effects (font (size 1.27 1.27) (thickness 0.15)) (justify left bottom) hide)
    )
    (pin "1")
    (instances
      (project "data-center-rdimm-ddr4-tester"
        (path ""
          (reference "#PWR038") (unit 1)
        )
      )
    )
  )

  (symbol (lib_id "antmicropower:GND") (at 103.505 99.06 0) (mirror y) (unit 1)
    (in_bom yes) (on_board yes) (dnp no) (fields_autoplaced)
    (property "Reference" "#PWR040" (at 103.505 105.41 0)
      (effects (font (size 1.27 1.27)) hide)
    )
    (property "Value" "GND" (at 103.505 103.505 0)
      (effects (font (size 1.27 1.27)))
    )
    (property "Footprint" "" (at 103.505 99.06 0)
      (effects (font (size 1.27 1.27)) hide)
    )
    (property "Datasheet" "" (at 103.505 99.06 0)
      (effects (font (size 1.27 1.27)) hide)
    )
    (property "Author" "Antmicro" (at 94.615 106.68 0)
      (effects (font (size 1.27 1.27) (thickness 0.15)) (justify left bottom) hide)
    )
    (property "License" "Apache-2.0" (at 94.615 109.22 0)
      (effects (font (size 1.27 1.27) (thickness 0.15)) (justify left bottom) hide)
    )
    (pin "1")
    (instances
      (project "data-center-rdimm-ddr4-tester"
        (path ""
          (reference "#PWR040") (unit 1)
        )
      )
    )
  )

  (symbol (lib_id "antmicropower:GND") (at 34.925 151.13 0) (mirror y) (unit 1)
    (in_bom yes) (on_board yes) (dnp no) (fields_autoplaced)
    (property "Reference" "#PWR041" (at 34.925 157.48 0)
      (effects (font (size 1.27 1.27)) hide)
    )
    (property "Value" "GND" (at 34.925 155.575 0)
      (effects (font (size 1.27 1.27)))
    )
    (property "Footprint" "" (at 34.925 151.13 0)
      (effects (font (size 1.27 1.27)) hide)
    )
    (property "Datasheet" "" (at 34.925 151.13 0)
      (effects (font (size 1.27 1.27)) hide)
    )
    (property "Author" "Antmicro" (at 26.035 158.75 0)
      (effects (font (size 1.27 1.27) (thickness 0.15)) (justify left bottom) hide)
    )
    (property "License" "Apache-2.0" (at 26.035 161.29 0)
      (effects (font (size 1.27 1.27) (thickness 0.15)) (justify left bottom) hide)
    )
    (pin "1")
    (instances
      (project "data-center-rdimm-ddr4-tester"
        (path ""
          (reference "#PWR041") (unit 1)
        )
      )
    )
  )

  (symbol (lib_id "antmicropower:GND") (at 33.02 244.475 0) (unit 1)
    (in_bom yes) (on_board yes) (dnp no) (fields_autoplaced)
    (property "Reference" "#PWR042" (at 33.02 250.825 0)
      (effects (font (size 1.27 1.27)) hide)
    )
    (property "Value" "GND" (at 33.02 249.555 0)
      (effects (font (size 1.27 1.27)))
    )
    (property "Footprint" "" (at 33.02 244.475 0)
      (effects (font (size 1.27 1.27)) hide)
    )
    (property "Datasheet" "" (at 33.02 244.475 0)
      (effects (font (size 1.27 1.27)) hide)
    )
    (property "Author" "Antmicro" (at 41.91 252.095 0)
      (effects (font (size 1.27 1.27) (thickness 0.15)) (justify left bottom) hide)
    )
    (property "License" "Apache-2.0" (at 41.91 254.635 0)
      (effects (font (size 1.27 1.27) (thickness 0.15)) (justify left bottom) hide)
    )
    (pin "1")
    (instances
      (project "data-center-rdimm-ddr4-tester"
        (path ""
          (reference "#PWR042") (unit 1)
        )
      )
    )
  )

  (symbol (lib_id "antmicroResistors0402:R_220R_0402") (at 90.805 226.695 270) (mirror x) (unit 1)
    (in_bom yes) (on_board yes) (dnp no) (fields_autoplaced)
    (property "Reference" "R62" (at 88.9 222.885 90)
      (effects (font (size 1.524 1.524)) (justify right))
    )
    (property "Value" "R_220R_0402" (at 78.105 206.375 0)
      (effects (font (size 1.27 1.27) (thickness 0.15)) (justify left bottom) hide)
    )
    (property "Footprint" "antmicro-footprints:R_0402_1005Metric" (at 75.565 206.375 0)
      (effects (font (size 1.27 1.27) (thickness 0.15)) (justify left bottom) hide)
    )
    (property "Datasheet" "https://www.bourns.com/docs/product-datasheets/cr.pdf" (at 73.025 206.375 0)
      (effects (font (size 1.27 1.27) (thickness 0.15)) (justify left bottom) hide)
    )
    (property "Manufacturer" "Bourns" (at 67.945 206.375 0)
      (effects (font (size 1.27 1.27) (thickness 0.15)) (justify left bottom) hide)
    )
    (property "MPN" "CR0402-FX-2200GLF" (at 70.485 206.375 0)
      (effects (font (size 1.27 1.27) (thickness 0.15)) (justify left bottom) hide)
    )
    (property "Val" "220R" (at 88.9 226.0599 90)
      (effects (font (size 1.27 1.27) (thickness 0.15)) (justify right))
    )
    (property "License" "Apache-2.0" (at 65.405 206.375 0)
      (effects (font (size 1.27 1.27) (thickness 0.15)) (justify left bottom) hide)
    )
    (property "Author" "Antmicro" (at 62.865 206.375 0)
      (effects (font (size 1.27 1.27) (thickness 0.15)) (justify left bottom) hide)
    )
    (property "Tolerance" "1%" (at 80.645 206.375 0)
      (effects (font (size 1.27 1.27)) (justify left bottom) hide)
    )
    (pin "1")
    (pin "2")
    (instances
      (project "data-center-rdimm-ddr4-tester"
        (path ""
          (reference "R62") (unit 1)
        )
      )
    )
  )

  (symbol (lib_id "antmicroResistors0402:R_220R_0402") (at 93.98 226.695 270) (mirror x) (unit 1)
    (in_bom yes) (on_board yes) (dnp no) (fields_autoplaced)
    (property "Reference" "R67" (at 95.885 222.885 90)
      (effects (font (size 1.524 1.524)) (justify left))
    )
    (property "Value" "R_220R_0402" (at 81.28 206.375 0)
      (effects (font (size 1.27 1.27) (thickness 0.15)) (justify left bottom) hide)
    )
    (property "Footprint" "antmicro-footprints:R_0402_1005Metric" (at 78.74 206.375 0)
      (effects (font (size 1.27 1.27) (thickness 0.15)) (justify left bottom) hide)
    )
    (property "Datasheet" "https://www.bourns.com/docs/product-datasheets/cr.pdf" (at 76.2 206.375 0)
      (effects (font (size 1.27 1.27) (thickness 0.15)) (justify left bottom) hide)
    )
    (property "Manufacturer" "Bourns" (at 71.12 206.375 0)
      (effects (font (size 1.27 1.27) (thickness 0.15)) (justify left bottom) hide)
    )
    (property "MPN" "CR0402-FX-2200GLF" (at 73.66 206.375 0)
      (effects (font (size 1.27 1.27) (thickness 0.15)) (justify left bottom) hide)
    )
    (property "Val" "220R" (at 95.885 226.0599 90)
      (effects (font (size 1.27 1.27) (thickness 0.15)) (justify left))
    )
    (property "License" "Apache-2.0" (at 68.58 206.375 0)
      (effects (font (size 1.27 1.27) (thickness 0.15)) (justify left bottom) hide)
    )
    (property "Author" "Antmicro" (at 66.04 206.375 0)
      (effects (font (size 1.27 1.27) (thickness 0.15)) (justify left bottom) hide)
    )
    (property "Tolerance" "1%" (at 83.82 206.375 0)
      (effects (font (size 1.27 1.27)) (justify left bottom) hide)
    )
    (pin "1")
    (pin "2")
    (instances
      (project "data-center-rdimm-ddr4-tester"
        (path ""
          (reference "R67") (unit 1)
        )
      )
    )
  )

  (symbol (lib_id "antmicroResistors0402:R_1k_0402") (at 180.34 157.48 0) (unit 1)
    (in_bom yes) (on_board yes) (dnp no)
    (property "Reference" "R78" (at 178.435 156.21 0)
      (effects (font (size 1.524 1.524)))
    )
    (property "Value" "R_1k_0402" (at 200.66 170.18 0)
      (effects (font (size 1.27 1.27) (thickness 0.15)) (justify left bottom) hide)
    )
    (property "Footprint" "antmicro-footprints:R_0402_1005Metric" (at 200.66 172.72 0)
      (effects (font (size 1.27 1.27) (thickness 0.15)) (justify left bottom) hide)
    )
    (property "Datasheet" "https://www.bourns.com/docs/product-datasheets/cr.pdf" (at 200.66 175.26 0)
      (effects (font (size 1.27 1.27) (thickness 0.15)) (justify left bottom) hide)
    )
    (property "Manufacturer" "Bourns" (at 200.66 180.34 0)
      (effects (font (size 1.27 1.27) (thickness 0.15)) (justify left bottom) hide)
    )
    (property "MPN" "CR0402-FX-1001GLF" (at 200.66 177.8 0)
      (effects (font (size 1.27 1.27) (thickness 0.15)) (justify left bottom) hide)
    )
    (property "Val" "1k" (at 187.325 156.21 0)
      (effects (font (size 1.27 1.27) (thickness 0.15)))
    )
    (property "License" "Apache-2.0" (at 200.66 182.88 0)
      (effects (font (size 1.27 1.27) (thickness 0.15)) (justify left bottom) hide)
    )
    (property "Author" "Antmicro" (at 200.66 185.42 0)
      (effects (font (size 1.27 1.27) (thickness 0.15)) (justify left bottom) hide)
    )
    (property "Tolerance" "1%" (at 200.66 167.64 0)
      (effects (font (size 1.27 1.27)) (justify left bottom) hide)
    )
    (pin "1")
    (pin "2")
    (instances
      (project "data-center-rdimm-ddr4-tester"
        (path ""
          (reference "R78") (unit 1)
        )
      )
    )
  )

  (symbol (lib_id "antmicroResistors0402:R_2k2_0402") (at 240.03 134.62 0) (unit 1)
    (in_bom yes) (on_board yes) (dnp no)
    (property "Reference" "R77" (at 238.125 133.35 0)
      (effects (font (size 1.524 1.524)))
    )
    (property "Value" "R_2k2_0402" (at 260.35 147.32 0)
      (effects (font (size 1.27 1.27) (thickness 0.15)) (justify left bottom) hide)
    )
    (property "Footprint" "antmicro-footprints:R_0402_1005Metric" (at 260.35 149.86 0)
      (effects (font (size 1.27 1.27) (thickness 0.15)) (justify left bottom) hide)
    )
    (property "Datasheet" "https://www.bourns.com/docs/product-datasheets/cr.pdf" (at 260.35 152.4 0)
      (effects (font (size 1.27 1.27) (thickness 0.15)) (justify left bottom) hide)
    )
    (property "Manufacturer" "Bourns" (at 260.35 157.48 0)
      (effects (font (size 1.27 1.27) (thickness 0.15)) (justify left bottom) hide)
    )
    (property "MPN" "CR0402-FX-2201GLF" (at 260.35 154.94 0)
      (effects (font (size 1.27 1.27) (thickness 0.15)) (justify left bottom) hide)
    )
    (property "Val" "2k2" (at 246.38 133.35 0)
      (effects (font (size 1.27 1.27) (thickness 0.15)))
    )
    (property "License" "Apache-2.0" (at 260.35 160.02 0)
      (effects (font (size 1.27 1.27) (thickness 0.15)) (justify left bottom) hide)
    )
    (property "Author" "Antmicro" (at 260.35 162.56 0)
      (effects (font (size 1.27 1.27) (thickness 0.15)) (justify left bottom) hide)
    )
    (property "Tolerance" "1%" (at 260.35 144.78 0)
      (effects (font (size 1.27 1.27)) (justify left bottom) hide)
    )
    (pin "1")
    (pin "2")
    (instances
      (project "data-center-rdimm-ddr4-tester"
        (path ""
          (reference "R77") (unit 1)
        )
      )
    )
  )

  (symbol (lib_id "antmicroResistors0402:R_2k2_0402") (at 240.03 137.16 0) (unit 1)
    (in_bom yes) (on_board yes) (dnp no)
    (property "Reference" "R89" (at 238.125 135.89 0)
      (effects (font (size 1.524 1.524)))
    )
    (property "Value" "R_2k2_0402" (at 260.35 149.86 0)
      (effects (font (size 1.27 1.27) (thickness 0.15)) (justify left bottom) hide)
    )
    (property "Footprint" "antmicro-footprints:R_0402_1005Metric" (at 260.35 152.4 0)
      (effects (font (size 1.27 1.27) (thickness 0.15)) (justify left bottom) hide)
    )
    (property "Datasheet" "https://www.bourns.com/docs/product-datasheets/cr.pdf" (at 260.35 154.94 0)
      (effects (font (size 1.27 1.27) (thickness 0.15)) (justify left bottom) hide)
    )
    (property "Manufacturer" "Bourns" (at 260.35 160.02 0)
      (effects (font (size 1.27 1.27) (thickness 0.15)) (justify left bottom) hide)
    )
    (property "MPN" "CR0402-FX-2201GLF" (at 260.35 157.48 0)
      (effects (font (size 1.27 1.27) (thickness 0.15)) (justify left bottom) hide)
    )
    (property "Val" "2k2" (at 246.38 135.89 0)
      (effects (font (size 1.27 1.27) (thickness 0.15)))
    )
    (property "License" "Apache-2.0" (at 260.35 162.56 0)
      (effects (font (size 1.27 1.27) (thickness 0.15)) (justify left bottom) hide)
    )
    (property "Author" "Antmicro" (at 260.35 165.1 0)
      (effects (font (size 1.27 1.27) (thickness 0.15)) (justify left bottom) hide)
    )
    (property "Tolerance" "1%" (at 260.35 147.32 0)
      (effects (font (size 1.27 1.27)) (justify left bottom) hide)
    )
    (pin "1")
    (pin "2")
    (instances
      (project "data-center-rdimm-ddr4-tester"
        (path ""
          (reference "R89") (unit 1)
        )
      )
    )
  )

  (symbol (lib_id "antmicroResistors0402:R_2k2_0402") (at 240.03 139.7 0) (unit 1)
    (in_bom no) (on_board yes) (dnp yes)
    (property "Reference" "R90" (at 238.125 138.43 0)
      (effects (font (size 1.524 1.524)))
    )
    (property "Value" "R_2k2_0402" (at 260.35 152.4 0)
      (effects (font (size 1.27 1.27) (thickness 0.15)) (justify left bottom) hide)
    )
    (property "Footprint" "antmicro-footprints:R_0402_1005Metric" (at 260.35 154.94 0)
      (effects (font (size 1.27 1.27) (thickness 0.15)) (justify left bottom) hide)
    )
    (property "Datasheet" "https://www.bourns.com/docs/product-datasheets/cr.pdf" (at 260.35 157.48 0)
      (effects (font (size 1.27 1.27) (thickness 0.15)) (justify left bottom) hide)
    )
    (property "Manufacturer" "Bourns" (at 260.35 162.56 0)
      (effects (font (size 1.27 1.27) (thickness 0.15)) (justify left bottom) hide)
    )
    (property "MPN" "CR0402-FX-2201GLF" (at 260.35 160.02 0)
      (effects (font (size 1.27 1.27) (thickness 0.15)) (justify left bottom) hide)
    )
    (property "Val" "2k2" (at 246.38 138.43 0)
      (effects (font (size 1.27 1.27) (thickness 0.15)))
    )
    (property "License" "Apache-2.0" (at 260.35 165.1 0)
      (effects (font (size 1.27 1.27) (thickness 0.15)) (justify left bottom) hide)
    )
    (property "Author" "Antmicro" (at 260.35 167.64 0)
      (effects (font (size 1.27 1.27) (thickness 0.15)) (justify left bottom) hide)
    )
    (property "Tolerance" "1%" (at 260.35 149.86 0)
      (effects (font (size 1.27 1.27)) (justify left bottom) hide)
    )
    (property "DNP" "DNP" (at 242.57 139.7 0)
      (effects (font (size 1.27 1.27)))
    )
    (pin "1")
    (pin "2")
    (instances
      (project "data-center-rdimm-ddr4-tester"
        (path ""
          (reference "R90") (unit 1)
        )
      )
    )
  )

  (symbol (lib_id "antmicroResistors0402:R_2k2_0402") (at 240.03 142.24 0) (unit 1)
    (in_bom no) (on_board yes) (dnp yes)
    (property "Reference" "R91" (at 238.125 140.97 0)
      (effects (font (size 1.524 1.524)))
    )
    (property "Value" "R_2k2_0402" (at 260.35 154.94 0)
      (effects (font (size 1.27 1.27) (thickness 0.15)) (justify left bottom) hide)
    )
    (property "Footprint" "antmicro-footprints:R_0402_1005Metric" (at 260.35 157.48 0)
      (effects (font (size 1.27 1.27) (thickness 0.15)) (justify left bottom) hide)
    )
    (property "Datasheet" "https://www.bourns.com/docs/product-datasheets/cr.pdf" (at 260.35 160.02 0)
      (effects (font (size 1.27 1.27) (thickness 0.15)) (justify left bottom) hide)
    )
    (property "Manufacturer" "Bourns" (at 260.35 165.1 0)
      (effects (font (size 1.27 1.27) (thickness 0.15)) (justify left bottom) hide)
    )
    (property "MPN" "CR0402-FX-2201GLF" (at 260.35 162.56 0)
      (effects (font (size 1.27 1.27) (thickness 0.15)) (justify left bottom) hide)
    )
    (property "Val" "2k2" (at 246.38 140.97 0)
      (effects (font (size 1.27 1.27) (thickness 0.15)))
    )
    (property "License" "Apache-2.0" (at 260.35 167.64 0)
      (effects (font (size 1.27 1.27) (thickness 0.15)) (justify left bottom) hide)
    )
    (property "Author" "Antmicro" (at 260.35 170.18 0)
      (effects (font (size 1.27 1.27) (thickness 0.15)) (justify left bottom) hide)
    )
    (property "Tolerance" "1%" (at 260.35 152.4 0)
      (effects (font (size 1.27 1.27)) (justify left bottom) hide)
    )
    (property "DNP" "DNP" (at 242.57 142.24 0)
      (effects (font (size 1.27 1.27)))
    )
    (pin "1")
    (pin "2")
    (instances
      (project "data-center-rdimm-ddr4-tester"
        (path ""
          (reference "R91") (unit 1)
        )
      )
    )
  )

  (symbol (lib_id "antmicroResistors0402:R_2k2_0402") (at 240.03 144.78 0) (unit 1)
    (in_bom yes) (on_board yes) (dnp no)
    (property "Reference" "R92" (at 238.125 143.51 0)
      (effects (font (size 1.524 1.524)))
    )
    (property "Value" "R_2k2_0402" (at 260.35 157.48 0)
      (effects (font (size 1.27 1.27) (thickness 0.15)) (justify left bottom) hide)
    )
    (property "Footprint" "antmicro-footprints:R_0402_1005Metric" (at 260.35 160.02 0)
      (effects (font (size 1.27 1.27) (thickness 0.15)) (justify left bottom) hide)
    )
    (property "Datasheet" "https://www.bourns.com/docs/product-datasheets/cr.pdf" (at 260.35 162.56 0)
      (effects (font (size 1.27 1.27) (thickness 0.15)) (justify left bottom) hide)
    )
    (property "Manufacturer" "Bourns" (at 260.35 167.64 0)
      (effects (font (size 1.27 1.27) (thickness 0.15)) (justify left bottom) hide)
    )
    (property "MPN" "CR0402-FX-2201GLF" (at 260.35 165.1 0)
      (effects (font (size 1.27 1.27) (thickness 0.15)) (justify left bottom) hide)
    )
    (property "Val" "2k2" (at 246.38 143.51 0)
      (effects (font (size 1.27 1.27) (thickness 0.15)))
    )
    (property "License" "Apache-2.0" (at 260.35 170.18 0)
      (effects (font (size 1.27 1.27) (thickness 0.15)) (justify left bottom) hide)
    )
    (property "Author" "Antmicro" (at 260.35 172.72 0)
      (effects (font (size 1.27 1.27) (thickness 0.15)) (justify left bottom) hide)
    )
    (property "Tolerance" "1%" (at 260.35 154.94 0)
      (effects (font (size 1.27 1.27)) (justify left bottom) hide)
    )
    (pin "1")
    (pin "2")
    (instances
      (project "data-center-rdimm-ddr4-tester"
        (path ""
          (reference "R92") (unit 1)
        )
      )
    )
  )

  (symbol (lib_id "antmicroResistors0402:R_2k2_0402") (at 240.03 147.32 0) (unit 1)
    (in_bom yes) (on_board yes) (dnp no)
    (property "Reference" "R93" (at 238.125 146.05 0)
      (effects (font (size 1.524 1.524)))
    )
    (property "Value" "R_2k2_0402" (at 260.35 160.02 0)
      (effects (font (size 1.27 1.27) (thickness 0.15)) (justify left bottom) hide)
    )
    (property "Footprint" "antmicro-footprints:R_0402_1005Metric" (at 260.35 162.56 0)
      (effects (font (size 1.27 1.27) (thickness 0.15)) (justify left bottom) hide)
    )
    (property "Datasheet" "https://www.bourns.com/docs/product-datasheets/cr.pdf" (at 260.35 165.1 0)
      (effects (font (size 1.27 1.27) (thickness 0.15)) (justify left bottom) hide)
    )
    (property "Manufacturer" "Bourns" (at 260.35 170.18 0)
      (effects (font (size 1.27 1.27) (thickness 0.15)) (justify left bottom) hide)
    )
    (property "MPN" "CR0402-FX-2201GLF" (at 260.35 167.64 0)
      (effects (font (size 1.27 1.27) (thickness 0.15)) (justify left bottom) hide)
    )
    (property "Val" "2k2" (at 246.38 146.05 0)
      (effects (font (size 1.27 1.27) (thickness 0.15)))
    )
    (property "License" "Apache-2.0" (at 260.35 172.72 0)
      (effects (font (size 1.27 1.27) (thickness 0.15)) (justify left bottom) hide)
    )
    (property "Author" "Antmicro" (at 260.35 175.26 0)
      (effects (font (size 1.27 1.27) (thickness 0.15)) (justify left bottom) hide)
    )
    (property "Tolerance" "1%" (at 260.35 157.48 0)
      (effects (font (size 1.27 1.27)) (justify left bottom) hide)
    )
    (pin "1")
    (pin "2")
    (instances
      (project "data-center-rdimm-ddr4-tester"
        (path ""
          (reference "R93") (unit 1)
        )
      )
    )
  )

  (symbol (lib_id "antmicroResistors0402:R_2k2_0402") (at 240.03 152.4 0) (unit 1)
    (in_bom no) (on_board yes) (dnp yes)
    (property "Reference" "R95" (at 238.125 151.13 0)
      (effects (font (size 1.524 1.524)))
    )
    (property "Value" "R_2k2_0402" (at 260.35 165.1 0)
      (effects (font (size 1.27 1.27) (thickness 0.15)) (justify left bottom) hide)
    )
    (property "Footprint" "antmicro-footprints:R_0402_1005Metric" (at 260.35 167.64 0)
      (effects (font (size 1.27 1.27) (thickness 0.15)) (justify left bottom) hide)
    )
    (property "Datasheet" "https://www.bourns.com/docs/product-datasheets/cr.pdf" (at 260.35 170.18 0)
      (effects (font (size 1.27 1.27) (thickness 0.15)) (justify left bottom) hide)
    )
    (property "Manufacturer" "Bourns" (at 260.35 175.26 0)
      (effects (font (size 1.27 1.27) (thickness 0.15)) (justify left bottom) hide)
    )
    (property "MPN" "CR0402-FX-2201GLF" (at 260.35 172.72 0)
      (effects (font (size 1.27 1.27) (thickness 0.15)) (justify left bottom) hide)
    )
    (property "Val" "2k2" (at 246.38 151.13 0)
      (effects (font (size 1.27 1.27) (thickness 0.15)))
    )
    (property "License" "Apache-2.0" (at 260.35 177.8 0)
      (effects (font (size 1.27 1.27) (thickness 0.15)) (justify left bottom) hide)
    )
    (property "Author" "Antmicro" (at 260.35 180.34 0)
      (effects (font (size 1.27 1.27) (thickness 0.15)) (justify left bottom) hide)
    )
    (property "Tolerance" "1%" (at 260.35 162.56 0)
      (effects (font (size 1.27 1.27)) (justify left bottom) hide)
    )
    (property "DNP" "DNP" (at 242.57 152.4 0)
      (effects (font (size 1.27 1.27)))
    )
    (pin "1")
    (pin "2")
    (instances
      (project "data-center-rdimm-ddr4-tester"
        (path ""
          (reference "R95") (unit 1)
        )
      )
    )
  )

  (symbol (lib_id "antmicroResistors0402:R_2k2_0402") (at 240.03 154.94 0) (unit 1)
    (in_bom no) (on_board yes) (dnp yes)
    (property "Reference" "R96" (at 238.125 153.67 0)
      (effects (font (size 1.524 1.524)))
    )
    (property "Value" "R_2k2_0402" (at 260.35 167.64 0)
      (effects (font (size 1.27 1.27) (thickness 0.15)) (justify left bottom) hide)
    )
    (property "Footprint" "antmicro-footprints:R_0402_1005Metric" (at 260.35 170.18 0)
      (effects (font (size 1.27 1.27) (thickness 0.15)) (justify left bottom) hide)
    )
    (property "Datasheet" "https://www.bourns.com/docs/product-datasheets/cr.pdf" (at 260.35 172.72 0)
      (effects (font (size 1.27 1.27) (thickness 0.15)) (justify left bottom) hide)
    )
    (property "Manufacturer" "Bourns" (at 260.35 177.8 0)
      (effects (font (size 1.27 1.27) (thickness 0.15)) (justify left bottom) hide)
    )
    (property "MPN" "CR0402-FX-2201GLF" (at 260.35 175.26 0)
      (effects (font (size 1.27 1.27) (thickness 0.15)) (justify left bottom) hide)
    )
    (property "Val" "2k2" (at 246.38 153.67 0)
      (effects (font (size 1.27 1.27) (thickness 0.15)))
    )
    (property "License" "Apache-2.0" (at 260.35 180.34 0)
      (effects (font (size 1.27 1.27) (thickness 0.15)) (justify left bottom) hide)
    )
    (property "Author" "Antmicro" (at 260.35 182.88 0)
      (effects (font (size 1.27 1.27) (thickness 0.15)) (justify left bottom) hide)
    )
    (property "Tolerance" "1%" (at 260.35 165.1 0)
      (effects (font (size 1.27 1.27)) (justify left bottom) hide)
    )
    (property "DNP" "DNP" (at 242.57 154.94 0)
      (effects (font (size 1.27 1.27)))
    )
    (pin "1")
    (pin "2")
    (instances
      (project "data-center-rdimm-ddr4-tester"
        (path ""
          (reference "R96") (unit 1)
        )
      )
    )
  )

  (symbol (lib_id "antmicroResistors0402:R_2k2_0402") (at 240.03 149.86 0) (unit 1)
    (in_bom no) (on_board yes) (dnp yes)
    (property "Reference" "R94" (at 238.125 148.59 0)
      (effects (font (size 1.524 1.524)))
    )
    (property "Value" "R_2k2_0402" (at 260.35 162.56 0)
      (effects (font (size 1.27 1.27) (thickness 0.15)) (justify left bottom) hide)
    )
    (property "Footprint" "antmicro-footprints:R_0402_1005Metric" (at 260.35 165.1 0)
      (effects (font (size 1.27 1.27) (thickness 0.15)) (justify left bottom) hide)
    )
    (property "Datasheet" "https://www.bourns.com/docs/product-datasheets/cr.pdf" (at 260.35 167.64 0)
      (effects (font (size 1.27 1.27) (thickness 0.15)) (justify left bottom) hide)
    )
    (property "Manufacturer" "Bourns" (at 260.35 172.72 0)
      (effects (font (size 1.27 1.27) (thickness 0.15)) (justify left bottom) hide)
    )
    (property "MPN" "CR0402-FX-2201GLF" (at 260.35 170.18 0)
      (effects (font (size 1.27 1.27) (thickness 0.15)) (justify left bottom) hide)
    )
    (property "Val" "2k2" (at 246.38 148.59 0)
      (effects (font (size 1.27 1.27) (thickness 0.15)))
    )
    (property "License" "Apache-2.0" (at 260.35 175.26 0)
      (effects (font (size 1.27 1.27) (thickness 0.15)) (justify left bottom) hide)
    )
    (property "Author" "Antmicro" (at 260.35 177.8 0)
      (effects (font (size 1.27 1.27) (thickness 0.15)) (justify left bottom) hide)
    )
    (property "Tolerance" "1%" (at 260.35 160.02 0)
      (effects (font (size 1.27 1.27)) (justify left bottom) hide)
    )
    (property "DNP" "DNP" (at 242.57 149.86 0)
      (effects (font (size 1.27 1.27)))
    )
    (pin "1")
    (pin "2")
    (instances
      (project "data-center-rdimm-ddr4-tester"
        (path ""
          (reference "R94") (unit 1)
        )
      )
    )
  )

  (symbol (lib_id "antmicropower:GND") (at 255.905 156.21 0) (unit 1)
    (in_bom yes) (on_board yes) (dnp no) (fields_autoplaced)
    (property "Reference" "#PWR0129" (at 255.905 162.56 0)
      (effects (font (size 1.27 1.27)) hide)
    )
    (property "Value" "GND" (at 255.905 161.29 0)
      (effects (font (size 1.27 1.27)))
    )
    (property "Footprint" "" (at 255.905 156.21 0)
      (effects (font (size 1.27 1.27)) hide)
    )
    (property "Datasheet" "" (at 255.905 156.21 0)
      (effects (font (size 1.27 1.27)) hide)
    )
    (property "Author" "Antmicro" (at 264.795 163.83 0)
      (effects (font (size 1.27 1.27) (thickness 0.15)) (justify left bottom) hide)
    )
    (property "License" "Apache-2.0" (at 264.795 166.37 0)
      (effects (font (size 1.27 1.27) (thickness 0.15)) (justify left bottom) hide)
    )
    (pin "1")
    (instances
      (project "data-center-rdimm-ddr4-tester"
        (path ""
          (reference "#PWR0129") (unit 1)
        )
      )
    )
  )

  (symbol (lib_id "antmicroResistorsmisc:R_0R_0201") (at 363.22 136.525 180) (unit 1)
    (in_bom yes) (on_board yes) (dnp no)
    (property "Reference" "R110" (at 355.6 135.255 0)
      (effects (font (size 1.524 1.524)))
    )
    (property "Value" "R_0R_0201" (at 342.9 123.825 0)
      (effects (font (size 1.27 1.27) (thickness 0.15)) (justify left bottom) hide)
    )
    (property "Footprint" "antmicro-footprints:R_0201" (at 342.9 121.285 0)
      (effects (font (size 1.27 1.27) (thickness 0.15)) (justify left bottom) hide)
    )
    (property "Datasheet" "https://www.bourns.com/docs/product-datasheets/cr.pdf" (at 342.9 118.745 0)
      (effects (font (size 1.27 1.27) (thickness 0.15)) (justify left bottom) hide)
    )
    (property "Manufacturer" "Bourns" (at 342.9 113.665 0)
      (effects (font (size 1.27 1.27) (thickness 0.15)) (justify left bottom) hide)
    )
    (property "MPN" "CR0201-FX-0R00GLF" (at 342.9 116.205 0)
      (effects (font (size 1.27 1.27) (thickness 0.15)) (justify left bottom) hide)
    )
    (property "Val" "0R" (at 364.49 135.255 0)
      (effects (font (size 1.27 1.27) (thickness 0.15)))
    )
    (property "License" "Apache-2.0" (at 342.9 111.125 0)
      (effects (font (size 1.27 1.27) (thickness 0.15)) (justify left bottom) hide)
    )
    (property "Author" "Antmicro" (at 342.9 108.585 0)
      (effects (font (size 1.27 1.27) (thickness 0.15)) (justify left bottom) hide)
    )
    (property "Tolerance" "1%" (at 342.9 126.365 0)
      (effects (font (size 1.27 1.27)) (justify left bottom) hide)
    )
    (pin "1")
    (pin "2")
    (instances
      (project "data-center-rdimm-ddr4-tester"
        (path ""
          (reference "R110") (unit 1)
        )
      )
    )
  )

  (symbol (lib_id "antmicroCapacitorsmisc:C_47u_16V_1206") (at 376.555 206.375 270) (unit 1)
    (in_bom yes) (on_board yes) (dnp no)
    (property "Reference" "C227" (at 375.285 207.645 0)
      (effects (font (size 1.524 1.524)) (justify right))
    )
    (property "Value" "C_47u_16V_1206" (at 366.395 226.695 0)
      (effects (font (size 1.27 1.27) (thickness 0.15)) (justify left bottom) hide)
    )
    (property "Footprint" "antmicro-footprints:C_1206_3216Metric" (at 363.855 226.695 0)
      (effects (font (size 1.27 1.27) (thickness 0.15)) (justify left bottom) hide)
    )
    (property "Datasheet" " " (at 361.315 226.695 0)
      (effects (font (size 1.27 1.27) (thickness 0.15)) (justify left bottom) hide)
    )
    (property "Manufacturer" "TDK" (at 356.235 226.695 0)
      (effects (font (size 1.27 1.27) (thickness 0.15)) (justify left bottom) hide)
    )
    (property "MPN" "C3216X5R1C476M160AB" (at 358.775 226.695 0)
      (effects (font (size 1.27 1.27) (thickness 0.15)) (justify left bottom) hide)
    )
    (property "Val" "47u/16V" (at 377.825 208.28 0)
      (effects (font (size 1.27 1.27) (thickness 0.15)) (justify right))
    )
    (property "License" "Apache-2.0" (at 353.695 226.695 0)
      (effects (font (size 1.27 1.27) (thickness 0.15)) (justify left bottom) hide)
    )
    (property "Author" "Antmicro" (at 351.155 226.695 0)
      (effects (font (size 1.27 1.27) (thickness 0.15)) (justify left bottom) hide)
    )
    (property "Voltage" "" (at 348.615 226.695 0)
      (effects (font (size 1.27 1.27)) (justify left bottom) hide)
    )
    (property "Dielectric" "" (at 346.075 226.695 0)
      (effects (font (size 1.27 1.27)) (justify left bottom) hide)
    )
    (pin "1")
    (pin "2")
    (instances
      (project "data-center-rdimm-ddr4-tester"
        (path ""
          (reference "C227") (unit 1)
        )
      )
    )
  )

  (symbol (lib_id "antmicropower:GNDD") (at 309.245 213.995 0) (unit 1)
    (in_bom yes) (on_board yes) (dnp no) (fields_autoplaced)
    (property "Reference" "#PWR016" (at 309.245 220.345 0)
      (effects (font (size 1.27 1.27)) hide)
    )
    (property "Value" "GNDD" (at 309.245 219.075 0)
      (effects (font (size 1.27 1.27)))
    )
    (property "Footprint" "" (at 309.245 213.995 0)
      (effects (font (size 1.27 1.27)) hide)
    )
    (property "Datasheet" "" (at 309.245 213.995 0)
      (effects (font (size 1.27 1.27)) hide)
    )
    (property "Author" "Antmicro" (at 324.485 221.615 0)
      (effects (font (size 1.27 1.27) (thickness 0.15)) (justify left bottom) hide)
    )
    (property "License" "Apache-2.0" (at 324.485 224.155 0)
      (effects (font (size 1.27 1.27) (thickness 0.15)) (justify left bottom) hide)
    )
    (pin "1")
    (instances
      (project "data-center-rdimm-ddr4-tester"
        (path ""
          (reference "#PWR016") (unit 1)
        )
      )
    )
  )

  (symbol (lib_id "antmicropower:GNDD") (at 302.26 213.995 0) (unit 1)
    (in_bom yes) (on_board yes) (dnp no) (fields_autoplaced)
    (property "Reference" "#PWR0316" (at 302.26 220.345 0)
      (effects (font (size 1.27 1.27)) hide)
    )
    (property "Value" "GNDD" (at 302.26 219.075 0)
      (effects (font (size 1.27 1.27)))
    )
    (property "Footprint" "" (at 302.26 213.995 0)
      (effects (font (size 1.27 1.27)) hide)
    )
    (property "Datasheet" "" (at 302.26 213.995 0)
      (effects (font (size 1.27 1.27)) hide)
    )
    (property "Author" "Antmicro" (at 317.5 221.615 0)
      (effects (font (size 1.27 1.27) (thickness 0.15)) (justify left bottom) hide)
    )
    (property "License" "Apache-2.0" (at 317.5 224.155 0)
      (effects (font (size 1.27 1.27) (thickness 0.15)) (justify left bottom) hide)
    )
    (pin "1")
    (instances
      (project "data-center-rdimm-ddr4-tester"
        (path ""
          (reference "#PWR0316") (unit 1)
        )
      )
    )
  )

  (symbol (lib_id "antmicroLogicSignalSwitchesMultiplexersDecoders:TS3L500RHUR") (at 334.645 25.4 0) (unit 1)
    (in_bom yes) (on_board yes) (dnp no) (fields_autoplaced)
    (property "Reference" "U16" (at 347.98 17.145 0)
      (effects (font (size 1.524 1.524)))
    )
    (property "Value" "TS3L500RHUR" (at 347.98 19.685 0)
      (effects (font (size 1.27 1.27) (thickness 0.15)))
    )
    (property "Footprint" "antmicro-footprints:WQFN-56-1EP_5x11x1mm_P0.5mm" (at 375.285 35.56 0)
      (effects (font (size 1.27 1.27) (thickness 0.15)) (justify left bottom) hide)
    )
    (property "Datasheet" "https://www.ti.com/lit/ds/symlink/ts3l500.pdf?ts=1663940859045&ref_url=https%253A%252F%252Fwww.google.com%252F" (at 375.285 38.1 0)
      (effects (font (size 1.27 1.27) (thickness 0.15)) (justify left bottom) hide)
    )
    (property "Manufacturer" "Texas Instruments" (at 375.285 40.64 0)
      (effects (font (size 1.27 1.27) (thickness 0.15)) (justify left bottom) hide)
    )
    (property "MPN" "TS3L500RHUR" (at 375.285 43.18 0)
      (effects (font (size 1.27 1.27) (thickness 0.15)) (justify left bottom) hide)
    )
    (property "Author" "Antmicro" (at 375.285 45.72 0)
      (effects (font (size 1.27 1.27) (thickness 0.15)) (justify left bottom) hide)
    )
    (property "License" "Apache-2.0" (at 375.285 48.26 0)
      (effects (font (size 1.27 1.27) (thickness 0.15)) (justify left bottom) hide)
    )
    (pin "1")
    (pin "10")
    (pin "11")
    (pin "12")
    (pin "13")
    (pin "14")
    (pin "15")
    (pin "16")
    (pin "17")
    (pin "18")
    (pin "19")
    (pin "2")
    (pin "20")
    (pin "21")
    (pin "22")
    (pin "23")
    (pin "24")
    (pin "25")
    (pin "26")
    (pin "27")
    (pin "28")
    (pin "29")
    (pin "3")
    (pin "30")
    (pin "31")
    (pin "32")
    (pin "33")
    (pin "34")
    (pin "35")
    (pin "36")
    (pin "37")
    (pin "38")
    (pin "39")
    (pin "4")
    (pin "40")
    (pin "41")
    (pin "42")
    (pin "43")
    (pin "44")
    (pin "45")
    (pin "46")
    (pin "47")
    (pin "48")
    (pin "49")
    (pin "5")
    (pin "50")
    (pin "51")
    (pin "52")
    (pin "53")
    (pin "54")
    (pin "55")
    (pin "56")
    (pin "57")
    (pin "6")
    (pin "7")
    (pin "8")
    (pin "9")
    (instances
      (project "data-center-rdimm-ddr4-tester"
        (path ""
          (reference "U16") (unit 1)
        )
      )
    )
  )

  (symbol (lib_id "antmicroDiodesRectifiersSingle:PDS760") (at 389.89 199.39 0) (unit 1)
    (in_bom yes) (on_board yes) (dnp no) (fields_autoplaced)
    (property "Reference" "D16" (at 393.954 192.405 0)
      (effects (font (size 1.524 1.524)))
    )
    (property "Value" "PDS760" (at 393.954 194.945 0)
      (effects (font (size 1.27 1.27) (thickness 0.15)))
    )
    (property "Footprint" "antmicro-footprints:PowerDI5" (at 412.75 209.55 0)
      (effects (font (size 1.27 1.27) (thickness 0.15)) (justify left bottom) hide)
    )
    (property "Datasheet" "https://www.diodes.com/assets/Datasheets/ds30470.pdf" (at 412.75 212.09 0)
      (effects (font (size 1.27 1.27) (thickness 0.15)) (justify left bottom) hide)
    )
    (property "Manufacturer" "Diodes Incorporated" (at 412.75 214.63 0)
      (effects (font (size 1.27 1.27) (thickness 0.15)) (justify left bottom) hide)
    )
    (property "MPN" "PDS760-13" (at 412.75 217.17 0)
      (effects (font (size 1.27 1.27) (thickness 0.15)) (justify left bottom) hide)
    )
    (property "Author" "Antmicro" (at 412.75 219.71 0)
      (effects (font (size 1.27 1.27) (thickness 0.15)) (justify left bottom) hide)
    )
    (property "License" "Apache-2.0" (at 412.75 222.25 0)
      (effects (font (size 1.27 1.27) (thickness 0.15)) (justify left bottom) hide)
    )
    (pin "A")
    (pin "C")
    (instances
      (project "data-center-rdimm-ddr4-tester"
        (path ""
          (reference "D16") (unit 1)
        )
      )
    )
  )

  (symbol (lib_id "antmicroResistors0402:R_49k9_0402") (at 220.345 234.95 0) (unit 1)
    (in_bom yes) (on_board yes) (dnp no)
    (property "Reference" "R159" (at 217.805 233.68 0)
      (effects (font (size 1.524 1.524)))
    )
    (property "Value" "R_49k9_0402" (at 240.665 247.65 0)
      (effects (font (size 1.27 1.27) (thickness 0.15)) (justify left bottom) hide)
    )
    (property "Footprint" "antmicro-footprints:R_0402_1005Metric" (at 240.665 250.19 0)
      (effects (font (size 1.27 1.27) (thickness 0.15)) (justify left bottom) hide)
    )
    (property "Datasheet" "https://www.bourns.com/docs/product-datasheets/cr.pdf" (at 240.665 252.73 0)
      (effects (font (size 1.27 1.27) (thickness 0.15)) (justify left bottom) hide)
    )
    (property "Manufacturer" "Bourns" (at 240.665 257.81 0)
      (effects (font (size 1.27 1.27) (thickness 0.15)) (justify left bottom) hide)
    )
    (property "MPN" "CR0402-FX-4992GLF" (at 240.665 255.27 0)
      (effects (font (size 1.27 1.27) (thickness 0.15)) (justify left bottom) hide)
    )
    (property "Val" "49k9" (at 227.33 233.68 0)
      (effects (font (size 1.27 1.27) (thickness 0.15)))
    )
    (property "License" "Apache-2.0" (at 240.665 260.35 0)
      (effects (font (size 1.27 1.27) (thickness 0.15)) (justify left bottom) hide)
    )
    (property "Author" "Antmicro" (at 240.665 262.89 0)
      (effects (font (size 1.27 1.27) (thickness 0.15)) (justify left bottom) hide)
    )
    (property "Tolerance" "1%" (at 240.665 245.11 0)
      (effects (font (size 1.27 1.27)) (justify left bottom) hide)
    )
    (pin "1")
    (pin "2")
    (instances
      (project "data-center-rdimm-ddr4-tester"
        (path ""
          (reference "R159") (unit 1)
        )
      )
    )
  )

  (symbol (lib_id "antmicroResistorsmisc:R_0R_0201") (at 332.105 133.985 0) (unit 1)
    (in_bom yes) (on_board yes) (dnp no)
    (property "Reference" "R101" (at 329.565 132.715 0)
      (effects (font (size 1.524 1.524)))
    )
    (property "Value" "R_0R_0201" (at 352.425 146.685 0)
      (effects (font (size 1.27 1.27) (thickness 0.15)) (justify left bottom) hide)
    )
    (property "Footprint" "antmicro-footprints:R_0201" (at 352.425 149.225 0)
      (effects (font (size 1.27 1.27) (thickness 0.15)) (justify left bottom) hide)
    )
    (property "Datasheet" "https://www.bourns.com/docs/product-datasheets/cr.pdf" (at 352.425 151.765 0)
      (effects (font (size 1.27 1.27) (thickness 0.15)) (justify left bottom) hide)
    )
    (property "Manufacturer" "Bourns" (at 352.425 156.845 0)
      (effects (font (size 1.27 1.27) (thickness 0.15)) (justify left bottom) hide)
    )
    (property "MPN" "CR0201-FX-0R00GLF" (at 352.425 154.305 0)
      (effects (font (size 1.27 1.27) (thickness 0.15)) (justify left bottom) hide)
    )
    (property "Val" "0R" (at 338.455 132.715 0)
      (effects (font (size 1.27 1.27) (thickness 0.15)))
    )
    (property "License" "Apache-2.0" (at 352.425 159.385 0)
      (effects (font (size 1.27 1.27) (thickness 0.15)) (justify left bottom) hide)
    )
    (property "Author" "Antmicro" (at 352.425 161.925 0)
      (effects (font (size 1.27 1.27) (thickness 0.15)) (justify left bottom) hide)
    )
    (property "Tolerance" "1%" (at 352.425 144.145 0)
      (effects (font (size 1.27 1.27)) (justify left bottom) hide)
    )
    (pin "1")
    (pin "2")
    (instances
      (project "data-center-rdimm-ddr4-tester"
        (path ""
          (reference "R101") (unit 1)
        )
      )
    )
  )

  (symbol (lib_id "antmicroResistorsmisc:R_0R_0201") (at 332.105 144.78 0) (unit 1)
    (in_bom yes) (on_board yes) (dnp no)
    (property "Reference" "R103" (at 329.565 143.51 0)
      (effects (font (size 1.524 1.524)))
    )
    (property "Value" "R_0R_0201" (at 352.425 157.48 0)
      (effects (font (size 1.27 1.27) (thickness 0.15)) (justify left bottom) hide)
    )
    (property "Footprint" "antmicro-footprints:R_0201" (at 352.425 160.02 0)
      (effects (font (size 1.27 1.27) (thickness 0.15)) (justify left bottom) hide)
    )
    (property "Datasheet" "https://www.bourns.com/docs/product-datasheets/cr.pdf" (at 352.425 162.56 0)
      (effects (font (size 1.27 1.27) (thickness 0.15)) (justify left bottom) hide)
    )
    (property "Manufacturer" "Bourns" (at 352.425 167.64 0)
      (effects (font (size 1.27 1.27) (thickness 0.15)) (justify left bottom) hide)
    )
    (property "MPN" "CR0201-FX-0R00GLF" (at 352.425 165.1 0)
      (effects (font (size 1.27 1.27) (thickness 0.15)) (justify left bottom) hide)
    )
    (property "Val" "0R" (at 338.455 143.51 0)
      (effects (font (size 1.27 1.27) (thickness 0.15)))
    )
    (property "License" "Apache-2.0" (at 352.425 170.18 0)
      (effects (font (size 1.27 1.27) (thickness 0.15)) (justify left bottom) hide)
    )
    (property "Author" "Antmicro" (at 352.425 172.72 0)
      (effects (font (size 1.27 1.27) (thickness 0.15)) (justify left bottom) hide)
    )
    (property "Tolerance" "1%" (at 352.425 154.94 0)
      (effects (font (size 1.27 1.27)) (justify left bottom) hide)
    )
    (pin "1")
    (pin "2")
    (instances
      (project "data-center-rdimm-ddr4-tester"
        (path ""
          (reference "R103") (unit 1)
        )
      )
    )
  )

  (symbol (lib_id "antmicropower:GNDD") (at 370.84 238.76 0) (mirror y) (unit 1)
    (in_bom yes) (on_board yes) (dnp no) (fields_autoplaced)
    (property "Reference" "#PWR0315" (at 370.84 245.11 0)
      (effects (font (size 1.27 1.27)) hide)
    )
    (property "Value" "GNDD" (at 370.84 243.84 0)
      (effects (font (size 1.27 1.27)))
    )
    (property "Footprint" "" (at 370.84 238.76 0)
      (effects (font (size 1.27 1.27)) hide)
    )
    (property "Datasheet" "" (at 370.84 238.76 0)
      (effects (font (size 1.27 1.27)) hide)
    )
    (property "Author" "Antmicro" (at 355.6 246.38 0)
      (effects (font (size 1.27 1.27) (thickness 0.15)) (justify left bottom) hide)
    )
    (property "License" "Apache-2.0" (at 355.6 248.92 0)
      (effects (font (size 1.27 1.27) (thickness 0.15)) (justify left bottom) hide)
    )
    (pin "1")
    (instances
      (project "data-center-rdimm-ddr4-tester"
        (path ""
          (reference "#PWR0315") (unit 1)
        )
      )
    )
  )

  (symbol (lib_id "antmicroResistors0402:R_10k_0402") (at 273.685 207.01 90) (unit 1)
    (in_bom no) (on_board yes) (dnp yes)
    (property "Reference" "R181" (at 274.32 201.295 90)
      (effects (font (size 1.524 1.524)) (justify right))
    )
    (property "Value" "R_10k_0402" (at 286.385 186.69 0)
      (effects (font (size 1.27 1.27) (thickness 0.15)) (justify left bottom) hide)
    )
    (property "Footprint" "antmicro-footprints:R_0402_1005Metric" (at 288.925 186.69 0)
      (effects (font (size 1.27 1.27) (thickness 0.15)) (justify left bottom) hide)
    )
    (property "Datasheet" "https://www.bourns.com/docs/product-datasheets/cr.pdf" (at 291.465 186.69 0)
      (effects (font (size 1.27 1.27) (thickness 0.15)) (justify left bottom) hide)
    )
    (property "Manufacturer" "Bourns" (at 296.545 186.69 0)
      (effects (font (size 1.27 1.27) (thickness 0.15)) (justify left bottom) hide)
    )
    (property "MPN" "CR0402-FX-1002GLF" (at 294.005 186.69 0)
      (effects (font (size 1.27 1.27) (thickness 0.15)) (justify left bottom) hide)
    )
    (property "Val" "10k" (at 274.32 207.645 90)
      (effects (font (size 1.27 1.27) (thickness 0.15)) (justify right))
    )
    (property "License" "Apache-2.0" (at 299.085 186.69 0)
      (effects (font (size 1.27 1.27) (thickness 0.15)) (justify left bottom) hide)
    )
    (property "Author" "Antmicro" (at 301.625 186.69 0)
      (effects (font (size 1.27 1.27) (thickness 0.15)) (justify left bottom) hide)
    )
    (property "Tolerance" "1%" (at 283.845 186.69 0)
      (effects (font (size 1.27 1.27)) (justify left bottom) hide)
    )
    (property "DNP" "DNP" (at 273.685 204.47 0)
      (effects (font (size 1.27 1.27)))
    )
    (pin "1")
    (pin "2")
    (instances
      (project "data-center-rdimm-ddr4-tester"
        (path ""
          (reference "R181") (unit 1)
        )
      )
    )
  )

  (symbol (lib_id "antmicropower:GND") (at 386.715 215.9 0) (unit 1)
    (in_bom yes) (on_board yes) (dnp no) (fields_autoplaced)
    (property "Reference" "#PWR0312" (at 386.715 222.25 0)
      (effects (font (size 1.27 1.27)) hide)
    )
    (property "Value" "GND" (at 386.715 220.98 0)
      (effects (font (size 1.27 1.27)))
    )
    (property "Footprint" "" (at 386.715 215.9 0)
      (effects (font (size 1.27 1.27)) hide)
    )
    (property "Datasheet" "" (at 386.715 215.9 0)
      (effects (font (size 1.27 1.27)) hide)
    )
    (property "Author" "Antmicro" (at 395.605 223.52 0)
      (effects (font (size 1.27 1.27) (thickness 0.15)) (justify left bottom) hide)
    )
    (property "License" "Apache-2.0" (at 395.605 226.06 0)
      (effects (font (size 1.27 1.27) (thickness 0.15)) (justify left bottom) hide)
    )
    (pin "1")
    (instances
      (project "data-center-rdimm-ddr4-tester"
        (path ""
          (reference "#PWR0312") (unit 1)
        )
      )
    )
  )

  (symbol (lib_id "antmicroResistorsmisc:R_0R_0201") (at 332.105 110.49 0) (unit 1)
    (in_bom yes) (on_board yes) (dnp no)
    (property "Reference" "R97" (at 330.2 109.22 0)
      (effects (font (size 1.524 1.524)))
    )
    (property "Value" "R_0R_0201" (at 352.425 123.19 0)
      (effects (font (size 1.27 1.27) (thickness 0.15)) (justify left bottom) hide)
    )
    (property "Footprint" "antmicro-footprints:R_0201" (at 352.425 125.73 0)
      (effects (font (size 1.27 1.27) (thickness 0.15)) (justify left bottom) hide)
    )
    (property "Datasheet" "https://www.bourns.com/docs/product-datasheets/cr.pdf" (at 352.425 128.27 0)
      (effects (font (size 1.27 1.27) (thickness 0.15)) (justify left bottom) hide)
    )
    (property "Manufacturer" "Bourns" (at 352.425 133.35 0)
      (effects (font (size 1.27 1.27) (thickness 0.15)) (justify left bottom) hide)
    )
    (property "MPN" "CR0201-FX-0R00GLF" (at 352.425 130.81 0)
      (effects (font (size 1.27 1.27) (thickness 0.15)) (justify left bottom) hide)
    )
    (property "Val" "0R" (at 338.455 109.22 0)
      (effects (font (size 1.27 1.27) (thickness 0.15)))
    )
    (property "License" "Apache-2.0" (at 352.425 135.89 0)
      (effects (font (size 1.27 1.27) (thickness 0.15)) (justify left bottom) hide)
    )
    (property "Author" "Antmicro" (at 352.425 138.43 0)
      (effects (font (size 1.27 1.27) (thickness 0.15)) (justify left bottom) hide)
    )
    (property "Tolerance" "1%" (at 352.425 120.65 0)
      (effects (font (size 1.27 1.27)) (justify left bottom) hide)
    )
    (pin "1")
    (pin "2")
    (instances
      (project "data-center-rdimm-ddr4-tester"
        (path ""
          (reference "R97") (unit 1)
        )
      )
    )
  )

  (symbol (lib_id "antmicroCapacitors0402:C_100n_0402") (at 357.505 160.02 270) (unit 1)
    (in_bom no) (on_board yes) (dnp yes)
    (property "Reference" "C291" (at 358.14 160.655 90)
      (effects (font (size 1.524 1.524)) (justify left))
    )
    (property "Value" "C_100n_0402" (at 347.345 180.34 0)
      (effects (font (size 1.27 1.27) (thickness 0.15)) (justify left bottom) hide)
    )
    (property "Footprint" "antmicro-footprints:C_0402_1005Metric" (at 344.805 180.34 0)
      (effects (font (size 1.27 1.27) (thickness 0.15)) (justify left bottom) hide)
    )
    (property "Datasheet" "https://search.murata.co.jp/Ceramy/image/img/A01X/G101/ENG/GRM155R61H104KE14-01.pdf" (at 342.265 180.34 0)
      (effects (font (size 1.27 1.27) (thickness 0.15)) (justify left bottom) hide)
    )
    (property "Manufacturer" "Murata" (at 337.185 180.34 0)
      (effects (font (size 1.27 1.27) (thickness 0.15)) (justify left bottom) hide)
    )
    (property "MPN" "GRM155R61H104KE14D" (at 339.725 180.34 0)
      (effects (font (size 1.27 1.27) (thickness 0.15)) (justify left bottom) hide)
    )
    (property "Val" "100n" (at 358.14 164.465 90)
      (effects (font (size 1.27 1.27) (thickness 0.15)) (justify left))
    )
    (property "License" "Apache-2.0" (at 334.645 180.34 0)
      (effects (font (size 1.27 1.27) (thickness 0.15)) (justify left bottom) hide)
    )
    (property "Author" "Antmicro" (at 332.105 180.34 0)
      (effects (font (size 1.27 1.27) (thickness 0.15)) (justify left bottom) hide)
    )
    (property "Voltage" "50V" (at 329.565 180.34 0)
      (effects (font (size 1.27 1.27)) (justify left bottom) hide)
    )
    (property "Dielectric" "X5R" (at 327.025 180.34 0)
      (effects (font (size 1.27 1.27)) (justify left bottom) hide)
    )
    (property "DNP" "DNP" (at 357.505 167.894 90)
      (effects (font (size 1.27 1.27)))
    )
    (pin "1")
    (pin "2")
    (instances
      (project "data-center-rdimm-ddr4-tester"
        (path ""
          (reference "C291") (unit 1)
        )
      )
    )
  )

  (symbol (lib_id "antmicroCapacitors0402:C_100n_0402") (at 386.715 206.375 270) (unit 1)
    (in_bom yes) (on_board yes) (dnp no)
    (property "Reference" "C229" (at 387.35 207.01 90)
      (effects (font (size 1.524 1.524)) (justify left))
    )
    (property "Value" "C_100n_0402" (at 376.555 226.695 0)
      (effects (font (size 1.27 1.27) (thickness 0.15)) (justify left bottom) hide)
    )
    (property "Footprint" "antmicro-footprints:C_0402_1005Metric" (at 374.015 226.695 0)
      (effects (font (size 1.27 1.27) (thickness 0.15)) (justify left bottom) hide)
    )
    (property "Datasheet" "https://search.murata.co.jp/Ceramy/image/img/A01X/G101/ENG/GRM155R61H104KE14-01.pdf" (at 371.475 226.695 0)
      (effects (font (size 1.27 1.27) (thickness 0.15)) (justify left bottom) hide)
    )
    (property "Manufacturer" "Murata" (at 366.395 226.695 0)
      (effects (font (size 1.27 1.27) (thickness 0.15)) (justify left bottom) hide)
    )
    (property "MPN" "GRM155R61H104KE14D" (at 368.935 226.695 0)
      (effects (font (size 1.27 1.27) (thickness 0.15)) (justify left bottom) hide)
    )
    (property "Val" "100n" (at 387.35 210.82 90)
      (effects (font (size 1.27 1.27) (thickness 0.15)) (justify left))
    )
    (property "License" "Apache-2.0" (at 363.855 226.695 0)
      (effects (font (size 1.27 1.27) (thickness 0.15)) (justify left bottom) hide)
    )
    (property "Author" "Antmicro" (at 361.315 226.695 0)
      (effects (font (size 1.27 1.27) (thickness 0.15)) (justify left bottom) hide)
    )
    (property "Voltage" "50V" (at 358.775 226.695 0)
      (effects (font (size 1.27 1.27)) (justify left bottom) hide)
    )
    (property "Dielectric" "X5R" (at 356.235 226.695 0)
      (effects (font (size 1.27 1.27)) (justify left bottom) hide)
    )
    (pin "1")
    (pin "2")
    (instances
      (project "data-center-rdimm-ddr4-tester"
        (path ""
          (reference "C229") (unit 1)
        )
      )
    )
  )

  (symbol (lib_id "antmicroResistors0402:R_10k_0402") (at 180.34 142.24 0) (unit 1)
    (in_bom yes) (on_board yes) (dnp no)
    (property "Reference" "R73" (at 178.435 140.97 0)
      (effects (font (size 1.524 1.524)))
    )
    (property "Value" "R_10k_0402" (at 200.66 154.94 0)
      (effects (font (size 1.27 1.27) (thickness 0.15)) (justify left bottom) hide)
    )
    (property "Footprint" "antmicro-footprints:R_0402_1005Metric" (at 200.66 157.48 0)
      (effects (font (size 1.27 1.27) (thickness 0.15)) (justify left bottom) hide)
    )
    (property "Datasheet" "https://www.bourns.com/docs/product-datasheets/cr.pdf" (at 200.66 160.02 0)
      (effects (font (size 1.27 1.27) (thickness 0.15)) (justify left bottom) hide)
    )
    (property "Manufacturer" "Bourns" (at 200.66 165.1 0)
      (effects (font (size 1.27 1.27) (thickness 0.15)) (justify left bottom) hide)
    )
    (property "MPN" "CR0402-FX-1002GLF" (at 200.66 162.56 0)
      (effects (font (size 1.27 1.27) (thickness 0.15)) (justify left bottom) hide)
    )
    (property "Val" "10k" (at 187.325 140.97 0)
      (effects (font (size 1.27 1.27) (thickness 0.15)))
    )
    (property "License" "Apache-2.0" (at 200.66 167.64 0)
      (effects (font (size 1.27 1.27) (thickness 0.15)) (justify left bottom) hide)
    )
    (property "Author" "Antmicro" (at 200.66 170.18 0)
      (effects (font (size 1.27 1.27) (thickness 0.15)) (justify left bottom) hide)
    )
    (property "Tolerance" "1%" (at 200.66 152.4 0)
      (effects (font (size 1.27 1.27)) (justify left bottom) hide)
    )
    (pin "1")
    (pin "2")
    (instances
      (project "data-center-rdimm-ddr4-tester"
        (path ""
          (reference "R73") (unit 1)
        )
      )
    )
  )

  (symbol (lib_id "antmicroResistorsmisc:R_0R_0201") (at 358.14 133.985 0) (unit 1)
    (in_bom yes) (on_board yes) (dnp no)
    (property "Reference" "R109" (at 355.6 132.715 0)
      (effects (font (size 1.524 1.524)))
    )
    (property "Value" "R_0R_0201" (at 378.46 146.685 0)
      (effects (font (size 1.27 1.27) (thickness 0.15)) (justify left bottom) hide)
    )
    (property "Footprint" "antmicro-footprints:R_0201" (at 378.46 149.225 0)
      (effects (font (size 1.27 1.27) (thickness 0.15)) (justify left bottom) hide)
    )
    (property "Datasheet" "https://www.bourns.com/docs/product-datasheets/cr.pdf" (at 378.46 151.765 0)
      (effects (font (size 1.27 1.27) (thickness 0.15)) (justify left bottom) hide)
    )
    (property "Manufacturer" "Bourns" (at 378.46 156.845 0)
      (effects (font (size 1.27 1.27) (thickness 0.15)) (justify left bottom) hide)
    )
    (property "MPN" "CR0201-FX-0R00GLF" (at 378.46 154.305 0)
      (effects (font (size 1.27 1.27) (thickness 0.15)) (justify left bottom) hide)
    )
    (property "Val" "0R" (at 364.49 132.715 0)
      (effects (font (size 1.27 1.27) (thickness 0.15)))
    )
    (property "License" "Apache-2.0" (at 378.46 159.385 0)
      (effects (font (size 1.27 1.27) (thickness 0.15)) (justify left bottom) hide)
    )
    (property "Author" "Antmicro" (at 378.46 161.925 0)
      (effects (font (size 1.27 1.27) (thickness 0.15)) (justify left bottom) hide)
    )
    (property "Tolerance" "1%" (at 378.46 144.145 0)
      (effects (font (size 1.27 1.27)) (justify left bottom) hide)
    )
    (pin "1")
    (pin "2")
    (instances
      (project "data-center-rdimm-ddr4-tester"
        (path ""
          (reference "R109") (unit 1)
        )
      )
    )
  )

  (symbol (lib_id "antmicroCapacitors0402:C_100n_0402") (at 349.885 160.02 270) (unit 1)
    (in_bom no) (on_board yes) (dnp yes)
    (property "Reference" "C290" (at 350.52 160.655 90)
      (effects (font (size 1.524 1.524)) (justify left))
    )
    (property "Value" "C_100n_0402" (at 339.725 180.34 0)
      (effects (font (size 1.27 1.27) (thickness 0.15)) (justify left bottom) hide)
    )
    (property "Footprint" "antmicro-footprints:C_0402_1005Metric" (at 337.185 180.34 0)
      (effects (font (size 1.27 1.27) (thickness 0.15)) (justify left bottom) hide)
    )
    (property "Datasheet" "https://search.murata.co.jp/Ceramy/image/img/A01X/G101/ENG/GRM155R61H104KE14-01.pdf" (at 334.645 180.34 0)
      (effects (font (size 1.27 1.27) (thickness 0.15)) (justify left bottom) hide)
    )
    (property "Manufacturer" "Murata" (at 329.565 180.34 0)
      (effects (font (size 1.27 1.27) (thickness 0.15)) (justify left bottom) hide)
    )
    (property "MPN" "GRM155R61H104KE14D" (at 332.105 180.34 0)
      (effects (font (size 1.27 1.27) (thickness 0.15)) (justify left bottom) hide)
    )
    (property "Val" "100n" (at 350.52 164.465 90)
      (effects (font (size 1.27 1.27) (thickness 0.15)) (justify left))
    )
    (property "License" "Apache-2.0" (at 327.025 180.34 0)
      (effects (font (size 1.27 1.27) (thickness 0.15)) (justify left bottom) hide)
    )
    (property "Author" "Antmicro" (at 324.485 180.34 0)
      (effects (font (size 1.27 1.27) (thickness 0.15)) (justify left bottom) hide)
    )
    (property "Voltage" "50V" (at 321.945 180.34 0)
      (effects (font (size 1.27 1.27)) (justify left bottom) hide)
    )
    (property "Dielectric" "X5R" (at 319.405 180.34 0)
      (effects (font (size 1.27 1.27)) (justify left bottom) hide)
    )
    (property "DNP" "DNP" (at 349.885 167.894 90)
      (effects (font (size 1.27 1.27)))
    )
    (pin "1")
    (pin "2")
    (instances
      (project "data-center-rdimm-ddr4-tester"
        (path ""
          (reference "C290") (unit 1)
        )
      )
    )
  )

  (symbol (lib_id "antmicroCapacitors0402:C_100n_0402") (at 372.11 160.02 270) (unit 1)
    (in_bom no) (on_board yes) (dnp yes)
    (property "Reference" "C293" (at 372.745 160.655 90)
      (effects (font (size 1.524 1.524)) (justify left))
    )
    (property "Value" "C_100n_0402" (at 361.95 180.34 0)
      (effects (font (size 1.27 1.27) (thickness 0.15)) (justify left bottom) hide)
    )
    (property "Footprint" "antmicro-footprints:C_0402_1005Metric" (at 359.41 180.34 0)
      (effects (font (size 1.27 1.27) (thickness 0.15)) (justify left bottom) hide)
    )
    (property "Datasheet" "https://search.murata.co.jp/Ceramy/image/img/A01X/G101/ENG/GRM155R61H104KE14-01.pdf" (at 356.87 180.34 0)
      (effects (font (size 1.27 1.27) (thickness 0.15)) (justify left bottom) hide)
    )
    (property "Manufacturer" "Murata" (at 351.79 180.34 0)
      (effects (font (size 1.27 1.27) (thickness 0.15)) (justify left bottom) hide)
    )
    (property "MPN" "GRM155R61H104KE14D" (at 354.33 180.34 0)
      (effects (font (size 1.27 1.27) (thickness 0.15)) (justify left bottom) hide)
    )
    (property "Val" "100n" (at 372.745 164.465 90)
      (effects (font (size 1.27 1.27) (thickness 0.15)) (justify left))
    )
    (property "License" "Apache-2.0" (at 349.25 180.34 0)
      (effects (font (size 1.27 1.27) (thickness 0.15)) (justify left bottom) hide)
    )
    (property "Author" "Antmicro" (at 346.71 180.34 0)
      (effects (font (size 1.27 1.27) (thickness 0.15)) (justify left bottom) hide)
    )
    (property "Voltage" "50V" (at 344.17 180.34 0)
      (effects (font (size 1.27 1.27)) (justify left bottom) hide)
    )
    (property "Dielectric" "X5R" (at 341.63 180.34 0)
      (effects (font (size 1.27 1.27)) (justify left bottom) hide)
    )
    (property "DNP" "DNP" (at 372.11 167.894 90)
      (effects (font (size 1.27 1.27)))
    )
    (pin "1")
    (pin "2")
    (instances
      (project "data-center-rdimm-ddr4-tester"
        (path ""
          (reference "C293") (unit 1)
        )
      )
    )
  )

  (symbol (lib_id "antmicroCapacitors0402:C_100n_0402") (at 327.66 160.02 270) (unit 1)
    (in_bom no) (on_board yes) (dnp yes)
    (property "Reference" "C287" (at 328.295 160.655 90)
      (effects (font (size 1.524 1.524)) (justify left))
    )
    (property "Value" "C_100n_0402" (at 317.5 180.34 0)
      (effects (font (size 1.27 1.27) (thickness 0.15)) (justify left bottom) hide)
    )
    (property "Footprint" "antmicro-footprints:C_0402_1005Metric" (at 314.96 180.34 0)
      (effects (font (size 1.27 1.27) (thickness 0.15)) (justify left bottom) hide)
    )
    (property "Datasheet" "https://search.murata.co.jp/Ceramy/image/img/A01X/G101/ENG/GRM155R61H104KE14-01.pdf" (at 312.42 180.34 0)
      (effects (font (size 1.27 1.27) (thickness 0.15)) (justify left bottom) hide)
    )
    (property "Manufacturer" "Murata" (at 307.34 180.34 0)
      (effects (font (size 1.27 1.27) (thickness 0.15)) (justify left bottom) hide)
    )
    (property "MPN" "GRM155R61H104KE14D" (at 309.88 180.34 0)
      (effects (font (size 1.27 1.27) (thickness 0.15)) (justify left bottom) hide)
    )
    (property "Val" "100n" (at 328.295 164.465 90)
      (effects (font (size 1.27 1.27) (thickness 0.15)) (justify left))
    )
    (property "License" "Apache-2.0" (at 304.8 180.34 0)
      (effects (font (size 1.27 1.27) (thickness 0.15)) (justify left bottom) hide)
    )
    (property "Author" "Antmicro" (at 302.26 180.34 0)
      (effects (font (size 1.27 1.27) (thickness 0.15)) (justify left bottom) hide)
    )
    (property "Voltage" "50V" (at 299.72 180.34 0)
      (effects (font (size 1.27 1.27)) (justify left bottom) hide)
    )
    (property "Dielectric" "X5R" (at 297.18 180.34 0)
      (effects (font (size 1.27 1.27)) (justify left bottom) hide)
    )
    (property "DNP" "DNP" (at 327.66 167.894 90)
      (effects (font (size 1.27 1.27)))
    )
    (pin "1")
    (pin "2")
    (instances
      (project "data-center-rdimm-ddr4-tester"
        (path ""
          (reference "C287") (unit 1)
        )
      )
    )
  )

  (symbol (lib_id "antmicroResistorsmisc:R_0R_0201") (at 337.185 136.525 180) (unit 1)
    (in_bom yes) (on_board yes) (dnp no)
    (property "Reference" "R102" (at 329.565 135.255 0)
      (effects (font (size 1.524 1.524)))
    )
    (property "Value" "R_0R_0201" (at 316.865 123.825 0)
      (effects (font (size 1.27 1.27) (thickness 0.15)) (justify left bottom) hide)
    )
    (property "Footprint" "antmicro-footprints:R_0201" (at 316.865 121.285 0)
      (effects (font (size 1.27 1.27) (thickness 0.15)) (justify left bottom) hide)
    )
    (property "Datasheet" "https://www.bourns.com/docs/product-datasheets/cr.pdf" (at 316.865 118.745 0)
      (effects (font (size 1.27 1.27) (thickness 0.15)) (justify left bottom) hide)
    )
    (property "Manufacturer" "Bourns" (at 316.865 113.665 0)
      (effects (font (size 1.27 1.27) (thickness 0.15)) (justify left bottom) hide)
    )
    (property "MPN" "CR0201-FX-0R00GLF" (at 316.865 116.205 0)
      (effects (font (size 1.27 1.27) (thickness 0.15)) (justify left bottom) hide)
    )
    (property "Val" "0R" (at 338.455 135.255 0)
      (effects (font (size 1.27 1.27) (thickness 0.15)))
    )
    (property "License" "Apache-2.0" (at 316.865 111.125 0)
      (effects (font (size 1.27 1.27) (thickness 0.15)) (justify left bottom) hide)
    )
    (property "Author" "Antmicro" (at 316.865 108.585 0)
      (effects (font (size 1.27 1.27) (thickness 0.15)) (justify left bottom) hide)
    )
    (property "Tolerance" "1%" (at 316.865 126.365 0)
      (effects (font (size 1.27 1.27)) (justify left bottom) hide)
    )
    (pin "1")
    (pin "2")
    (instances
      (project "data-center-rdimm-ddr4-tester"
        (path ""
          (reference "R102") (unit 1)
        )
      )
    )
  )

  (symbol (lib_id "antmicroLEDIndicationDiscrete:LED_G_0603_KP-1608CGCK") (at 318.135 206.375 270) (unit 1)
    (in_bom yes) (on_board yes) (dnp no) (fields_autoplaced)
    (property "Reference" "D15" (at 321.31 208.915 90)
      (effects (font (size 1.524 1.524)) (justify left))
    )
    (property "Value" "LED_G_0603_KP-1608CGCK" (at 321.31 212.0899 90)
      (effects (font (size 1.27 1.27) (thickness 0.15)) (justify left) hide)
    )
    (property "Footprint" "antmicro-footprints:LED_0603_1608Metric_G" (at 307.975 229.235 0)
      (effects (font (size 1.27 1.27) (thickness 0.15)) (justify left bottom) hide)
    )
    (property "Datasheet" "http://www.farnell.com/datasheets/2045956.pdf" (at 305.435 229.235 0)
      (effects (font (size 1.27 1.27) (thickness 0.15)) (justify left bottom) hide)
    )
    (property "MPN" "KP-1608CGCK" (at 321.31 212.0899 90)
      (effects (font (size 1.27 1.27) (thickness 0.15)) (justify left))
    )
    (property "Manufacturer" "Kingbright" (at 300.355 229.235 0)
      (effects (font (size 1.27 1.27) (thickness 0.15)) (justify left bottom) hide)
    )
    (property "Author" "Antmicro" (at 297.815 229.235 0)
      (effects (font (size 1.27 1.27) (thickness 0.15)) (justify left bottom) hide)
    )
    (property "License" "Apache-2.0" (at 295.275 229.235 0)
      (effects (font (size 1.27 1.27) (thickness 0.15)) (justify left bottom) hide)
    )
    (pin "1")
    (pin "2")
    (instances
      (project "data-center-rdimm-ddr4-tester"
        (path ""
          (reference "D15") (unit 1)
        )
      )
    )
  )

  (symbol (lib_id "antmicroCapacitors0402:C_100n_0402") (at 342.9 160.02 270) (unit 1)
    (in_bom no) (on_board yes) (dnp yes)
    (property "Reference" "C289" (at 343.535 160.655 90)
      (effects (font (size 1.524 1.524)) (justify left))
    )
    (property "Value" "C_100n_0402" (at 332.74 180.34 0)
      (effects (font (size 1.27 1.27) (thickness 0.15)) (justify left bottom) hide)
    )
    (property "Footprint" "antmicro-footprints:C_0402_1005Metric" (at 330.2 180.34 0)
      (effects (font (size 1.27 1.27) (thickness 0.15)) (justify left bottom) hide)
    )
    (property "Datasheet" "https://search.murata.co.jp/Ceramy/image/img/A01X/G101/ENG/GRM155R61H104KE14-01.pdf" (at 327.66 180.34 0)
      (effects (font (size 1.27 1.27) (thickness 0.15)) (justify left bottom) hide)
    )
    (property "Manufacturer" "Murata" (at 322.58 180.34 0)
      (effects (font (size 1.27 1.27) (thickness 0.15)) (justify left bottom) hide)
    )
    (property "MPN" "GRM155R61H104KE14D" (at 325.12 180.34 0)
      (effects (font (size 1.27 1.27) (thickness 0.15)) (justify left bottom) hide)
    )
    (property "Val" "100n" (at 343.535 164.465 90)
      (effects (font (size 1.27 1.27) (thickness 0.15)) (justify left))
    )
    (property "License" "Apache-2.0" (at 320.04 180.34 0)
      (effects (font (size 1.27 1.27) (thickness 0.15)) (justify left bottom) hide)
    )
    (property "Author" "Antmicro" (at 317.5 180.34 0)
      (effects (font (size 1.27 1.27) (thickness 0.15)) (justify left bottom) hide)
    )
    (property "Voltage" "50V" (at 314.96 180.34 0)
      (effects (font (size 1.27 1.27)) (justify left bottom) hide)
    )
    (property "Dielectric" "X5R" (at 312.42 180.34 0)
      (effects (font (size 1.27 1.27)) (justify left bottom) hide)
    )
    (property "DNP" "DNP" (at 342.9 167.894 90)
      (effects (font (size 1.27 1.27)))
    )
    (pin "1")
    (pin "2")
    (instances
      (project "data-center-rdimm-ddr4-tester"
        (path ""
          (reference "C289") (unit 1)
        )
      )
    )
  )

  (symbol (lib_id "antmicropower:GNDD") (at 342.265 217.17 0) (unit 1)
    (in_bom yes) (on_board yes) (dnp no) (fields_autoplaced)
    (property "Reference" "#PWR0320" (at 342.265 223.52 0)
      (effects (font (size 1.27 1.27)) hide)
    )
    (property "Value" "GNDD" (at 342.265 222.25 0)
      (effects (font (size 1.27 1.27)))
    )
    (property "Footprint" "" (at 342.265 217.17 0)
      (effects (font (size 1.27 1.27)) hide)
    )
    (property "Datasheet" "" (at 342.265 217.17 0)
      (effects (font (size 1.27 1.27)) hide)
    )
    (property "Author" "Antmicro" (at 357.505 224.79 0)
      (effects (font (size 1.27 1.27) (thickness 0.15)) (justify left bottom) hide)
    )
    (property "License" "Apache-2.0" (at 357.505 227.33 0)
      (effects (font (size 1.27 1.27) (thickness 0.15)) (justify left bottom) hide)
    )
    (pin "1")
    (instances
      (project "data-center-rdimm-ddr4-tester"
        (path ""
          (reference "#PWR0320") (unit 1)
        )
      )
    )
  )

  (symbol (lib_id "antmicroResistors0402:R_10k_0402") (at 180.34 144.78 0) (unit 1)
    (in_bom no) (on_board yes) (dnp yes)
    (property "Reference" "R74" (at 178.435 143.51 0)
      (effects (font (size 1.524 1.524)))
    )
    (property "Value" "R_10k_0402" (at 200.66 157.48 0)
      (effects (font (size 1.27 1.27) (thickness 0.15)) (justify left bottom) hide)
    )
    (property "Footprint" "antmicro-footprints:R_0402_1005Metric" (at 200.66 160.02 0)
      (effects (font (size 1.27 1.27) (thickness 0.15)) (justify left bottom) hide)
    )
    (property "Datasheet" "https://www.bourns.com/docs/product-datasheets/cr.pdf" (at 200.66 162.56 0)
      (effects (font (size 1.27 1.27) (thickness 0.15)) (justify left bottom) hide)
    )
    (property "Manufacturer" "Bourns" (at 200.66 167.64 0)
      (effects (font (size 1.27 1.27) (thickness 0.15)) (justify left bottom) hide)
    )
    (property "MPN" "CR0402-FX-1002GLF" (at 200.66 165.1 0)
      (effects (font (size 1.27 1.27) (thickness 0.15)) (justify left bottom) hide)
    )
    (property "Val" "10k" (at 187.325 143.51 0)
      (effects (font (size 1.27 1.27) (thickness 0.15)))
    )
    (property "License" "Apache-2.0" (at 200.66 170.18 0)
      (effects (font (size 1.27 1.27) (thickness 0.15)) (justify left bottom) hide)
    )
    (property "Author" "Antmicro" (at 200.66 172.72 0)
      (effects (font (size 1.27 1.27) (thickness 0.15)) (justify left bottom) hide)
    )
    (property "Tolerance" "1%" (at 200.66 154.94 0)
      (effects (font (size 1.27 1.27)) (justify left bottom) hide)
    )
    (property "DNP" "DNP" (at 182.88 144.78 0)
      (effects (font (size 1.27 1.27)))
    )
    (pin "1")
    (pin "2")
    (instances
      (project "data-center-rdimm-ddr4-tester"
        (path ""
          (reference "R74") (unit 1)
        )
      )
    )
  )

  (symbol (lib_id "antmicroPMICPowerDistributionSwitchesLoadDrivers:TPS2372-3RGWR") (at 239.395 209.55 0) (unit 1)
    (in_bom yes) (on_board yes) (dnp no) (fields_autoplaced)
    (property "Reference" "U13" (at 250.19 247.65 0)
      (effects (font (size 1.27 1.27)))
    )
    (property "Value" "TPS2372-3RGWR" (at 250.19 250.19 0)
      (effects (font (size 1.27 1.27) (thickness 0.15)))
    )
    (property "Footprint" "antmicro-footprints:VQFN-20_5x5x1mm_P0.65mm" (at 274.955 214.63 0)
      (effects (font (size 1.27 1.27) (thickness 0.15)) (justify left bottom) hide)
    )
    (property "Datasheet" "https://www.ti.com/lit/ds/symlink/tps2372.pdf?ts=1679042478513&ref_url=https%253A%252F%252Fwww.google.com%252F" (at 274.955 217.17 0)
      (effects (font (size 1.27 1.27) (thickness 0.15)) (justify left bottom) hide)
    )
    (property "MPN" "TPS2372-3RGWR" (at 274.955 219.71 0)
      (effects (font (size 1.27 1.27) (thickness 0.15)) (justify left bottom) hide)
    )
    (property "Manufacturer" "Texas Instruments" (at 274.955 222.25 0)
      (effects (font (size 1.27 1.27) (thickness 0.15)) (justify left bottom) hide)
    )
    (property "Author" "Antmicro" (at 274.955 224.79 0)
      (effects (font (size 1.27 1.27) (thickness 0.15)) (justify left bottom) hide)
    )
    (property "License" "Apache-2.0" (at 274.955 227.33 0)
      (effects (font (size 1.27 1.27) (thickness 0.15)) (justify left bottom) hide)
    )
    (pin "1")
    (pin "10")
    (pin "11")
    (pin "12")
    (pin "13")
    (pin "14")
    (pin "15")
    (pin "16")
    (pin "17")
    (pin "18")
    (pin "19")
    (pin "2")
    (pin "20")
    (pin "21")
    (pin "3")
    (pin "4")
    (pin "5")
    (pin "6")
    (pin "7")
    (pin "8")
    (pin "9")
    (instances
      (project "data-center-rdimm-ddr4-tester"
        (path ""
          (reference "U13") (unit 1)
        )
      )
    )
  )

  (symbol (lib_id "antmicroResistors0402:R_32k4_0402") (at 318.135 205.74 90) (unit 1)
    (in_bom yes) (on_board yes) (dnp no) (fields_autoplaced)
    (property "Reference" "R180" (at 320.04 201.93 90)
      (effects (font (size 1.524 1.524)) (justify right))
    )
    (property "Value" "R_32k4_0402" (at 330.835 185.42 0)
      (effects (font (size 1.27 1.27) (thickness 0.15)) (justify left bottom) hide)
    )
    (property "Footprint" "antmicro-footprints:R_0402_1005Metric" (at 333.375 185.42 0)
      (effects (font (size 1.27 1.27) (thickness 0.15)) (justify left bottom) hide)
    )
    (property "Datasheet" "https://www.bourns.com/docs/product-datasheets/cr.pdf" (at 335.915 185.42 0)
      (effects (font (size 1.27 1.27) (thickness 0.15)) (justify left bottom) hide)
    )
    (property "Manufacturer" "Bourns" (at 340.995 185.42 0)
      (effects (font (size 1.27 1.27) (thickness 0.15)) (justify left bottom) hide)
    )
    (property "MPN" "CR0402-FX-3242GLF" (at 338.455 185.42 0)
      (effects (font (size 1.27 1.27) (thickness 0.15)) (justify left bottom) hide)
    )
    (property "Val" "32k4" (at 320.04 205.1049 90)
      (effects (font (size 1.27 1.27) (thickness 0.15)) (justify right))
    )
    (property "License" "Apache-2.0" (at 343.535 185.42 0)
      (effects (font (size 1.27 1.27) (thickness 0.15)) (justify left bottom) hide)
    )
    (property "Author" "Antmicro" (at 346.075 185.42 0)
      (effects (font (size 1.27 1.27) (thickness 0.15)) (justify left bottom) hide)
    )
    (property "Tolerance" "1%" (at 328.295 185.42 0)
      (effects (font (size 1.27 1.27)) (justify left bottom) hide)
    )
    (pin "1")
    (pin "2")
    (instances
      (project "data-center-rdimm-ddr4-tester"
        (path ""
          (reference "R180") (unit 1)
        )
      )
    )
  )

  (symbol (lib_id "antmicroResistors0603:R_63R4_0603") (at 227.965 226.695 90) (unit 1)
    (in_bom yes) (on_board yes) (dnp no) (fields_autoplaced)
    (property "Reference" "R176" (at 229.87 222.885 90)
      (effects (font (size 1.524 1.524)) (justify right))
    )
    (property "Value" "R_63R4_0603" (at 240.665 206.375 0)
      (effects (font (size 1.27 1.27) (thickness 0.15)) (justify left bottom) hide)
    )
    (property "Footprint" "antmicro-footprints:R_0603_1608Metric" (at 243.205 206.375 0)
      (effects (font (size 1.27 1.27) (thickness 0.15)) (justify left bottom) hide)
    )
    (property "Datasheet" "https://www.bourns.com/docs/product-datasheets/cr.pdf" (at 245.745 206.375 0)
      (effects (font (size 1.27 1.27) (thickness 0.15)) (justify left bottom) hide)
    )
    (property "Manufacturer" "Bourns" (at 250.825 206.375 0)
      (effects (font (size 1.27 1.27) (thickness 0.15)) (justify left bottom) hide)
    )
    (property "MPN" "CR0603-FX-63R4ELF" (at 248.285 206.375 0)
      (effects (font (size 1.27 1.27) (thickness 0.15)) (justify left bottom) hide)
    )
    (property "Val" "63R4" (at 229.87 226.0599 90)
      (effects (font (size 1.27 1.27) (thickness 0.15)) (justify right))
    )
    (property "License" "Apache-2.0" (at 253.365 206.375 0)
      (effects (font (size 1.27 1.27) (thickness 0.15)) (justify left bottom) hide)
    )
    (property "Author" "Antmicro" (at 255.905 206.375 0)
      (effects (font (size 1.27 1.27) (thickness 0.15)) (justify left bottom) hide)
    )
    (property "Tolerance" "1%" (at 238.125 206.375 0)
      (effects (font (size 1.27 1.27)) (justify left bottom) hide)
    )
    (pin "1")
    (pin "2")
    (instances
      (project "data-center-rdimm-ddr4-tester"
        (path ""
          (reference "R176") (unit 1)
        )
      )
    )
  )

  (symbol (lib_id "antmicroCapacitorsmisc:C_22u_100V_2220") (at 309.245 208.915 270) (unit 1)
    (in_bom yes) (on_board yes) (dnp no)
    (property "Reference" "C225" (at 307.975 204.47 0)
      (effects (font (size 1.524 1.524)) (justify left))
    )
    (property "Value" "C_22u_100V_2220" (at 299.085 229.235 0)
      (effects (font (size 1.27 1.27) (thickness 0.15)) (justify left bottom) hide)
    )
    (property "Footprint" "antmicro-footprints:C_2220_5650Metric" (at 296.545 229.235 0)
      (effects (font (size 1.27 1.27) (thickness 0.15)) (justify left bottom) hide)
    )
    (property "Datasheet" " " (at 294.005 229.235 0)
      (effects (font (size 1.27 1.27) (thickness 0.15)) (justify left bottom) hide)
    )
    (property "Manufacturer" "TDK" (at 288.925 229.235 0)
      (effects (font (size 1.27 1.27) (thickness 0.15)) (justify left bottom) hide)
    )
    (property "MPN" "C5750X7S2A226M280KB" (at 291.465 229.235 0)
      (effects (font (size 1.27 1.27) (thickness 0.15)) (justify left bottom) hide)
    )
    (property "Val" "22u/100V" (at 310.515 200.66 0)
      (effects (font (size 1.27 1.27) (thickness 0.15)) (justify left))
    )
    (property "License" "Apache-2.0" (at 286.385 229.235 0)
      (effects (font (size 1.27 1.27) (thickness 0.15)) (justify left bottom) hide)
    )
    (property "Author" "Antmicro" (at 283.845 229.235 0)
      (effects (font (size 1.27 1.27) (thickness 0.15)) (justify left bottom) hide)
    )
    (property "Voltage" "" (at 281.305 229.235 0)
      (effects (font (size 1.27 1.27)) (justify left bottom) hide)
    )
    (property "Dielectric" "" (at 278.765 229.235 0)
      (effects (font (size 1.27 1.27)) (justify left bottom) hide)
    )
    (pin "1")
    (pin "2")
    (instances
      (project "data-center-rdimm-ddr4-tester"
        (path ""
          (reference "C225") (unit 1)
        )
      )
    )
  )

  (symbol (lib_id "antmicroResistorsmisc:R_0R_0201") (at 332.105 122.555 0) (unit 1)
    (in_bom yes) (on_board yes) (dnp no)
    (property "Reference" "R99" (at 328.93 121.285 0)
      (effects (font (size 1.524 1.524)))
    )
    (property "Value" "R_0R_0201" (at 352.425 135.255 0)
      (effects (font (size 1.27 1.27) (thickness 0.15)) (justify left bottom) hide)
    )
    (property "Footprint" "antmicro-footprints:R_0201" (at 352.425 137.795 0)
      (effects (font (size 1.27 1.27) (thickness 0.15)) (justify left bottom) hide)
    )
    (property "Datasheet" "https://www.bourns.com/docs/product-datasheets/cr.pdf" (at 352.425 140.335 0)
      (effects (font (size 1.27 1.27) (thickness 0.15)) (justify left bottom) hide)
    )
    (property "Manufacturer" "Bourns" (at 352.425 145.415 0)
      (effects (font (size 1.27 1.27) (thickness 0.15)) (justify left bottom) hide)
    )
    (property "MPN" "CR0201-FX-0R00GLF" (at 352.425 142.875 0)
      (effects (font (size 1.27 1.27) (thickness 0.15)) (justify left bottom) hide)
    )
    (property "Val" "0R" (at 338.455 121.285 0)
      (effects (font (size 1.27 1.27) (thickness 0.15)))
    )
    (property "License" "Apache-2.0" (at 352.425 147.955 0)
      (effects (font (size 1.27 1.27) (thickness 0.15)) (justify left bottom) hide)
    )
    (property "Author" "Antmicro" (at 352.425 150.495 0)
      (effects (font (size 1.27 1.27) (thickness 0.15)) (justify left bottom) hide)
    )
    (property "Tolerance" "1%" (at 352.425 132.715 0)
      (effects (font (size 1.27 1.27)) (justify left bottom) hide)
    )
    (pin "1")
    (pin "2")
    (instances
      (project "data-center-rdimm-ddr4-tester"
        (path ""
          (reference "R99") (unit 1)
        )
      )
    )
  )

  (symbol (lib_id "antmicroResistors0402:R_0R_0402") (at 265.43 229.87 0) (unit 1)
    (in_bom yes) (on_board yes) (dnp no)
    (property "Reference" "R178" (at 267.97 226.06 0)
      (effects (font (size 1.524 1.524)))
    )
    (property "Value" "R_0R_0402" (at 285.75 242.57 0)
      (effects (font (size 1.27 1.27) (thickness 0.15)) (justify left bottom) hide)
    )
    (property "Footprint" "antmicro-footprints:R_0402_1005Metric" (at 285.75 245.11 0)
      (effects (font (size 1.27 1.27) (thickness 0.15)) (justify left bottom) hide)
    )
    (property "Datasheet" "https://industrial.panasonic.com/cdbs/www-data/pdf/RDA0000/AOA0000C301.pdf" (at 285.75 247.65 0)
      (effects (font (size 1.27 1.27) (thickness 0.15)) (justify left bottom) hide)
    )
    (property "Manufacturer" "Panasonic" (at 285.75 252.73 0)
      (effects (font (size 1.27 1.27) (thickness 0.15)) (justify left bottom) hide)
    )
    (property "MPN" "ERJ2GE0R00X" (at 285.75 250.19 0)
      (effects (font (size 1.27 1.27) (thickness 0.15)) (justify left bottom) hide)
    )
    (property "Val" "0R" (at 267.97 227.965 0)
      (effects (font (size 1.27 1.27) (thickness 0.15)))
    )
    (property "License" "Apache-2.0" (at 285.75 255.27 0)
      (effects (font (size 1.27 1.27) (thickness 0.15)) (justify left bottom) hide)
    )
    (property "Author" "Antmicro" (at 285.75 257.81 0)
      (effects (font (size 1.27 1.27) (thickness 0.15)) (justify left bottom) hide)
    )
    (property "Tolerance" "~" (at 285.75 240.03 0)
      (effects (font (size 1.27 1.27)) (justify left bottom) hide)
    )
    (property "Current" "1A" (at 285.75 260.35 0)
      (effects (font (size 1.27 1.27) (thickness 0.15)) (justify left bottom) hide)
    )
    (pin "1")
    (pin "2")
    (instances
      (project "data-center-rdimm-ddr4-tester"
        (path ""
          (reference "R178") (unit 1)
        )
      )
    )
  )

  (symbol (lib_id "antmicroOptoisolatorsLogicOutput:ACPL-217-500E") (at 346.71 233.68 0) (unit 1)
    (in_bom yes) (on_board yes) (dnp no) (fields_autoplaced)
    (property "Reference" "IC2" (at 353.187 226.695 0)
      (effects (font (size 1.27 1.27)))
    )
    (property "Value" "ACPL-217-500E" (at 353.187 229.235 0)
      (effects (font (size 1.27 1.27) (thickness 0.15)))
    )
    (property "Footprint" "antmicro-footprints:SOIC-4_4.55x2.6mm_P1.27mm" (at 374.65 243.84 0)
      (effects (font (size 1.27 1.27) (thickness 0.15)) (justify left bottom) hide)
    )
    (property "Datasheet" "https://docs.broadcom.com/doc/AV02-0470EN" (at 374.65 246.38 0)
      (effects (font (size 1.27 1.27) (thickness 0.15)) (justify left bottom) hide)
    )
    (property "Description" "Broadcom ACPL-217-500E DC Input Transistor Output Optocoupler, Surface Mount, 4-Pin SO" (at 374.65 248.92 0)
      (effects (font (size 1.27 1.27) (thickness 0.15)) (justify left bottom) hide)
    )
    (property "MPN" "ACPL-217-500E" (at 374.65 254 0)
      (effects (font (size 1.27 1.27) (thickness 0.15)) (justify left bottom) hide)
    )
    (property "Manufacturer" "Broadcom" (at 374.65 251.46 0)
      (effects (font (size 1.27 1.27) (thickness 0.15)) (justify left bottom) hide)
    )
    (property "Author" "Antmicro" (at 374.65 256.54 0)
      (effects (font (size 1.27 1.27) (thickness 0.15)) (justify left bottom) hide)
    )
    (property "License" "Apache-2.0" (at 374.65 259.08 0)
      (effects (font (size 1.27 1.27) (thickness 0.15)) (justify left bottom) hide)
    )
    (pin "1")
    (pin "2")
    (pin "3")
    (pin "4")
    (instances
      (project "data-center-rdimm-ddr4-tester"
        (path ""
          (reference "IC2") (unit 1)
        )
      )
    )
  )

  (symbol (lib_id "antmicroResistorsmisc:R_0R_0201") (at 292.735 144.78 0) (unit 1)
    (in_bom yes) (on_board yes) (dnp no)
    (property "Reference" "R221" (at 295.275 140.97 0)
      (effects (font (size 1.524 1.524)))
    )
    (property "Value" "R_0R_0201" (at 313.055 157.48 0)
      (effects (font (size 1.27 1.27) (thickness 0.15)) (justify left bottom) hide)
    )
    (property "Footprint" "antmicro-footprints:R_0201" (at 313.055 160.02 0)
      (effects (font (size 1.27 1.27) (thickness 0.15)) (justify left bottom) hide)
    )
    (property "Datasheet" "https://www.bourns.com/docs/product-datasheets/cr.pdf" (at 313.055 162.56 0)
      (effects (font (size 1.27 1.27) (thickness 0.15)) (justify left bottom) hide)
    )
    (property "Manufacturer" "Bourns" (at 313.055 167.64 0)
      (effects (font (size 1.27 1.27) (thickness 0.15)) (justify left bottom) hide)
    )
    (property "MPN" "CR0201-FX-0R00GLF" (at 313.055 165.1 0)
      (effects (font (size 1.27 1.27) (thickness 0.15)) (justify left bottom) hide)
    )
    (property "Val" "0R" (at 295.275 142.875 0)
      (effects (font (size 1.27 1.27) (thickness 0.15)))
    )
    (property "License" "Apache-2.0" (at 313.055 170.18 0)
      (effects (font (size 1.27 1.27) (thickness 0.15)) (justify left bottom) hide)
    )
    (property "Author" "Antmicro" (at 313.055 172.72 0)
      (effects (font (size 1.27 1.27) (thickness 0.15)) (justify left bottom) hide)
    )
    (property "Tolerance" "1%" (at 313.055 154.94 0)
      (effects (font (size 1.27 1.27)) (justify left bottom) hide)
    )
    (pin "1")
    (pin "2")
    (instances
      (project "data-center-rdimm-ddr4-tester"
        (path ""
          (reference "R221") (unit 1)
        )
      )
    )
  )

  (symbol (lib_id "antmicroResistorsmisc:R_0R_0201") (at 292.735 147.32 0) (unit 1)
    (in_bom yes) (on_board yes) (dnp no)
    (property "Reference" "R222" (at 295.275 149.86 0)
      (effects (font (size 1.524 1.524)))
    )
    (property "Value" "R_0R_0201" (at 313.055 160.02 0)
      (effects (font (size 1.27 1.27) (thickness 0.15)) (justify left bottom) hide)
    )
    (property "Footprint" "antmicro-footprints:R_0201" (at 313.055 162.56 0)
      (effects (font (size 1.27 1.27) (thickness 0.15)) (justify left bottom) hide)
    )
    (property "Datasheet" "https://www.bourns.com/docs/product-datasheets/cr.pdf" (at 313.055 165.1 0)
      (effects (font (size 1.27 1.27) (thickness 0.15)) (justify left bottom) hide)
    )
    (property "Manufacturer" "Bourns" (at 313.055 170.18 0)
      (effects (font (size 1.27 1.27) (thickness 0.15)) (justify left bottom) hide)
    )
    (property "MPN" "CR0201-FX-0R00GLF" (at 313.055 167.64 0)
      (effects (font (size 1.27 1.27) (thickness 0.15)) (justify left bottom) hide)
    )
    (property "Val" "0R" (at 295.275 151.765 0)
      (effects (font (size 1.27 1.27) (thickness 0.15)))
    )
    (property "License" "Apache-2.0" (at 313.055 172.72 0)
      (effects (font (size 1.27 1.27) (thickness 0.15)) (justify left bottom) hide)
    )
    (property "Author" "Antmicro" (at 313.055 175.26 0)
      (effects (font (size 1.27 1.27) (thickness 0.15)) (justify left bottom) hide)
    )
    (property "Tolerance" "1%" (at 313.055 157.48 0)
      (effects (font (size 1.27 1.27)) (justify left bottom) hide)
    )
    (pin "1")
    (pin "2")
    (instances
      (project "data-center-rdimm-ddr4-tester"
        (path ""
          (reference "R222") (unit 1)
        )
      )
    )
  )

  (symbol (lib_id "data-center-rdimm-ddr4-tester:C_100n_16V_0402") (at 36.83 235.585 270) (unit 1)
    (in_bom yes) (on_board yes) (dnp no) (fields_autoplaced)
    (property "Reference" "C312" (at 39.37 236.8613 90)
      (effects (font (size 1.524 1.524)) (justify left))
    )
    (property "Value" "C_100n_16V_0402" (at 26.67 255.905 0)
      (effects (font (size 1.27 1.27) (thickness 0.15)) (justify left bottom) hide)
    )
    (property "Footprint" "data-center-rdimm-ddr4-tester-footprints:C_0402_1005Metric" (at 24.13 255.905 0)
      (effects (font (size 1.27 1.27) (thickness 0.15)) (justify left bottom) hide)
    )
    (property "Datasheet" " " (at 21.59 255.905 0)
      (effects (font (size 1.27 1.27) (thickness 0.15)) (justify left bottom) hide)
    )
    (property "Manufacturer" "Multicomp" (at 16.51 255.905 0)
      (effects (font (size 1.27 1.27) (thickness 0.15)) (justify left bottom) hide)
    )
    (property "MPN" "MC0402B104K160CT" (at 19.05 255.905 0)
      (effects (font (size 1.27 1.27) (thickness 0.15)) (justify left bottom) hide)
    )
    (property "Val" "100n" (at 39.37 240.0362 90)
      (effects (font (size 1.27 1.27) (thickness 0.15)) (justify left))
    )
    (property "License" "Apache-2.0" (at 13.97 255.905 0)
      (effects (font (size 1.27 1.27) (thickness 0.15)) (justify left bottom) hide)
    )
    (property "Author" "Antmicro" (at 11.43 255.905 0)
      (effects (font (size 1.27 1.27) (thickness 0.15)) (justify left bottom) hide)
    )
    (property "Voltage" "" (at 8.89 255.905 0)
      (effects (font (size 1.27 1.27)) (justify left bottom) hide)
    )
    (property "Dielectric" "" (at 6.35 255.905 0)
      (effects (font (size 1.27 1.27)) (justify left bottom) hide)
    )
    (pin "1")
    (pin "2")
    (instances
      (project "data-center-rdimm-ddr4-tester"
        (path ""
          (reference "C312") (unit 1)
        )
      )
    )
  )

  (symbol (lib_id "antmicroResistorsmisc:R_0R_0201") (at 363.22 125.095 180) (unit 1)
    (in_bom yes) (on_board yes) (dnp no)
    (property "Reference" "R108" (at 355.6 123.825 0)
      (effects (font (size 1.524 1.524)))
    )
    (property "Value" "R_0R_0201" (at 342.9 112.395 0)
      (effects (font (size 1.27 1.27) (thickness 0.15)) (justify left bottom) hide)
    )
    (property "Footprint" "antmicro-footprints:R_0201" (at 342.9 109.855 0)
      (effects (font (size 1.27 1.27) (thickness 0.15)) (justify left bottom) hide)
    )
    (property "Datasheet" "https://www.bourns.com/docs/product-datasheets/cr.pdf" (at 342.9 107.315 0)
      (effects (font (size 1.27 1.27) (thickness 0.15)) (justify left bottom) hide)
    )
    (property "Manufacturer" "Bourns" (at 342.9 102.235 0)
      (effects (font (size 1.27 1.27) (thickness 0.15)) (justify left bottom) hide)
    )
    (property "MPN" "CR0201-FX-0R00GLF" (at 342.9 104.775 0)
      (effects (font (size 1.27 1.27) (thickness 0.15)) (justify left bottom) hide)
    )
    (property "Val" "0R" (at 364.49 123.825 0)
      (effects (font (size 1.27 1.27) (thickness 0.15)))
    )
    (property "License" "Apache-2.0" (at 342.9 99.695 0)
      (effects (font (size 1.27 1.27) (thickness 0.15)) (justify left bottom) hide)
    )
    (property "Author" "Antmicro" (at 342.9 97.155 0)
      (effects (font (size 1.27 1.27) (thickness 0.15)) (justify left bottom) hide)
    )
    (property "Tolerance" "1%" (at 342.9 114.935 0)
      (effects (font (size 1.27 1.27)) (justify left bottom) hide)
    )
    (pin "1")
    (pin "2")
    (instances
      (project "data-center-rdimm-ddr4-tester"
        (path ""
          (reference "R108") (unit 1)
        )
      )
    )
  )

  (symbol (lib_id "antmicropower:GNDD") (at 262.255 243.84 0) (unit 1)
    (in_bom yes) (on_board yes) (dnp no) (fields_autoplaced)
    (property "Reference" "#PWR014" (at 262.255 250.19 0)
      (effects (font (size 1.27 1.27)) hide)
    )
    (property "Value" "GNDD" (at 262.255 248.92 0)
      (effects (font (size 1.27 1.27)))
    )
    (property "Footprint" "" (at 262.255 243.84 0)
      (effects (font (size 1.27 1.27)) hide)
    )
    (property "Datasheet" "" (at 262.255 243.84 0)
      (effects (font (size 1.27 1.27)) hide)
    )
    (property "Author" "Antmicro" (at 277.495 251.46 0)
      (effects (font (size 1.27 1.27) (thickness 0.15)) (justify left bottom) hide)
    )
    (property "License" "Apache-2.0" (at 277.495 254 0)
      (effects (font (size 1.27 1.27) (thickness 0.15)) (justify left bottom) hide)
    )
    (pin "1")
    (instances
      (project "data-center-rdimm-ddr4-tester"
        (path ""
          (reference "#PWR014") (unit 1)
        )
      )
    )
  )

  (symbol (lib_id "antmicroTVSDiodes:CD-MMBL110S") (at 156.21 214.63 0) (unit 1)
    (in_bom yes) (on_board yes) (dnp no)
    (property "Reference" "D13" (at 165.1 208.915 0)
      (effects (font (size 1.27 1.27)))
    )
    (property "Value" "CD-MMBL110S" (at 165.1 211.455 0)
      (effects (font (size 1.27 1.27) (thickness 0.15)))
    )
    (property "Footprint" "antmicro-footprints:DFN3538" (at 182.88 222.25 0)
      (effects (font (size 1.27 1.27) (thickness 0.15)) (justify left bottom) hide)
    )
    (property "Datasheet" "https://www.bourns.com/docs/product-datasheets/CD-MMBL110S.pdf" (at 182.88 224.79 0)
      (effects (font (size 1.27 1.27) (thickness 0.15)) (justify left bottom) hide)
    )
    (property "MPN" "CD-MMBL110S" (at 182.88 227.33 0)
      (effects (font (size 1.27 1.27) (thickness 0.15)) (justify left bottom) hide)
    )
    (property "Manufacturer" "Bourns" (at 182.88 229.87 0)
      (effects (font (size 1.27 1.27) (thickness 0.15)) (justify left bottom) hide)
    )
    (property "Author" "Antmicro" (at 182.88 232.41 0)
      (effects (font (size 1.27 1.27) (thickness 0.15)) (justify left bottom) hide)
    )
    (property "License" "Apache-2.0" (at 182.88 234.95 0)
      (effects (font (size 1.27 1.27) (thickness 0.15)) (justify left bottom) hide)
    )
    (pin "1")
    (pin "2")
    (pin "3")
    (pin "4")
    (instances
      (project "data-center-rdimm-ddr4-tester"
        (path ""
          (reference "D13") (unit 1)
        )
      )
    )
  )

  (symbol (lib_id "antmicroResistors0402:R_10k_0402") (at 180.34 137.16 0) (unit 1)
    (in_bom no) (on_board yes) (dnp yes)
    (property "Reference" "R71" (at 178.435 135.89 0)
      (effects (font (size 1.524 1.524)))
    )
    (property "Value" "R_10k_0402" (at 200.66 149.86 0)
      (effects (font (size 1.27 1.27) (thickness 0.15)) (justify left bottom) hide)
    )
    (property "Footprint" "antmicro-footprints:R_0402_1005Metric" (at 200.66 152.4 0)
      (effects (font (size 1.27 1.27) (thickness 0.15)) (justify left bottom) hide)
    )
    (property "Datasheet" "https://www.bourns.com/docs/product-datasheets/cr.pdf" (at 200.66 154.94 0)
      (effects (font (size 1.27 1.27) (thickness 0.15)) (justify left bottom) hide)
    )
    (property "Manufacturer" "Bourns" (at 200.66 160.02 0)
      (effects (font (size 1.27 1.27) (thickness 0.15)) (justify left bottom) hide)
    )
    (property "MPN" "CR0402-FX-1002GLF" (at 200.66 157.48 0)
      (effects (font (size 1.27 1.27) (thickness 0.15)) (justify left bottom) hide)
    )
    (property "Val" "10k" (at 187.325 135.89 0)
      (effects (font (size 1.27 1.27) (thickness 0.15)))
    )
    (property "License" "Apache-2.0" (at 200.66 162.56 0)
      (effects (font (size 1.27 1.27) (thickness 0.15)) (justify left bottom) hide)
    )
    (property "Author" "Antmicro" (at 200.66 165.1 0)
      (effects (font (size 1.27 1.27) (thickness 0.15)) (justify left bottom) hide)
    )
    (property "Tolerance" "1%" (at 200.66 147.32 0)
      (effects (font (size 1.27 1.27)) (justify left bottom) hide)
    )
    (property "DNP" "DNP" (at 182.88 137.16 0)
      (effects (font (size 1.27 1.27)))
    )
    (pin "1")
    (pin "2")
    (instances
      (project "data-center-rdimm-ddr4-tester"
        (path ""
          (reference "R71") (unit 1)
        )
      )
    )
  )

  (symbol (lib_id "antmicroResistorsmisc:R_0R_0201") (at 363.22 147.32 180) (unit 1)
    (in_bom yes) (on_board yes) (dnp no)
    (property "Reference" "R112" (at 355.6 146.05 0)
      (effects (font (size 1.524 1.524)))
    )
    (property "Value" "R_0R_0201" (at 342.9 134.62 0)
      (effects (font (size 1.27 1.27) (thickness 0.15)) (justify left bottom) hide)
    )
    (property "Footprint" "antmicro-footprints:R_0201" (at 342.9 132.08 0)
      (effects (font (size 1.27 1.27) (thickness 0.15)) (justify left bottom) hide)
    )
    (property "Datasheet" "https://www.bourns.com/docs/product-datasheets/cr.pdf" (at 342.9 129.54 0)
      (effects (font (size 1.27 1.27) (thickness 0.15)) (justify left bottom) hide)
    )
    (property "Manufacturer" "Bourns" (at 342.9 124.46 0)
      (effects (font (size 1.27 1.27) (thickness 0.15)) (justify left bottom) hide)
    )
    (property "MPN" "CR0201-FX-0R00GLF" (at 342.9 127 0)
      (effects (font (size 1.27 1.27) (thickness 0.15)) (justify left bottom) hide)
    )
    (property "Val" "0R" (at 364.49 146.05 0)
      (effects (font (size 1.27 1.27) (thickness 0.15)))
    )
    (property "License" "Apache-2.0" (at 342.9 121.92 0)
      (effects (font (size 1.27 1.27) (thickness 0.15)) (justify left bottom) hide)
    )
    (property "Author" "Antmicro" (at 342.9 119.38 0)
      (effects (font (size 1.27 1.27) (thickness 0.15)) (justify left bottom) hide)
    )
    (property "Tolerance" "1%" (at 342.9 137.16 0)
      (effects (font (size 1.27 1.27)) (justify left bottom) hide)
    )
    (pin "1")
    (pin "2")
    (instances
      (project "data-center-rdimm-ddr4-tester"
        (path ""
          (reference "R112") (unit 1)
        )
      )
    )
  )

  (symbol (lib_id "antmicroResistors0402:R_10k_0402") (at 180.34 154.94 0) (unit 1)
    (in_bom yes) (on_board yes) (dnp no)
    (property "Reference" "R81" (at 178.435 153.67 0)
      (effects (font (size 1.524 1.524)))
    )
    (property "Value" "R_10k_0402" (at 200.66 167.64 0)
      (effects (font (size 1.27 1.27) (thickness 0.15)) (justify left bottom) hide)
    )
    (property "Footprint" "antmicro-footprints:R_0402_1005Metric" (at 200.66 170.18 0)
      (effects (font (size 1.27 1.27) (thickness 0.15)) (justify left bottom) hide)
    )
    (property "Datasheet" "https://www.bourns.com/docs/product-datasheets/cr.pdf" (at 200.66 172.72 0)
      (effects (font (size 1.27 1.27) (thickness 0.15)) (justify left bottom) hide)
    )
    (property "Manufacturer" "Bourns" (at 200.66 177.8 0)
      (effects (font (size 1.27 1.27) (thickness 0.15)) (justify left bottom) hide)
    )
    (property "MPN" "CR0402-FX-1002GLF" (at 200.66 175.26 0)
      (effects (font (size 1.27 1.27) (thickness 0.15)) (justify left bottom) hide)
    )
    (property "Val" "10k" (at 187.325 153.67 0)
      (effects (font (size 1.27 1.27) (thickness 0.15)))
    )
    (property "License" "Apache-2.0" (at 200.66 180.34 0)
      (effects (font (size 1.27 1.27) (thickness 0.15)) (justify left bottom) hide)
    )
    (property "Author" "Antmicro" (at 200.66 182.88 0)
      (effects (font (size 1.27 1.27) (thickness 0.15)) (justify left bottom) hide)
    )
    (property "Tolerance" "1%" (at 200.66 165.1 0)
      (effects (font (size 1.27 1.27)) (justify left bottom) hide)
    )
    (pin "1")
    (pin "2")
    (instances
      (project "data-center-rdimm-ddr4-tester"
        (path ""
          (reference "R81") (unit 1)
        )
      )
    )
  )

  (symbol (lib_id "antmicroDCDCConverters:PDQE30-Q48-S12-D") (at 343.535 199.39 0) (unit 1)
    (in_bom yes) (on_board yes) (dnp no) (fields_autoplaced)
    (property "Reference" "PS1" (at 353.695 191.77 0)
      (effects (font (size 1.27 1.27)))
    )
    (property "Value" "PDQE30-Q48-S12-D" (at 353.695 194.31 0)
      (effects (font (size 1.27 1.27) (thickness 0.15)))
    )
    (property "Footprint" "antmicro-footprints:CONV_PDQE30-Q48-S5-D" (at 379.095 207.01 0)
      (effects (font (size 1.27 1.27) (thickness 0.15)) (justify left bottom) hide)
    )
    (property "Datasheet" "https://www.cui.com/product/resource/pdqe30-d.pdf" (at 379.095 209.55 0)
      (effects (font (size 1.27 1.27) (thickness 0.15)) (justify left bottom) hide)
    )
    (property "MPN" "PDQE30-Q48-S12-D" (at 379.095 214.63 0)
      (effects (font (size 1.27 1.27) (thickness 0.15)) (justify left bottom) hide)
    )
    (property "Manufacturer" "CUI Inc" (at 379.095 217.17 0)
      (effects (font (size 1.27 1.27) (thickness 0.15)) (justify left bottom) hide)
    )
    (property "Author" "Antmicro" (at 379.095 219.71 0)
      (effects (font (size 1.27 1.27) (thickness 0.15)) (justify left bottom) hide)
    )
    (property "License" "Apache-2.0" (at 379.095 222.25 0)
      (effects (font (size 1.27 1.27) (thickness 0.15)) (justify left bottom) hide)
    )
    (pin "1")
    (pin "2")
    (pin "3")
    (pin "4")
    (pin "5")
    (pin "6")
    (instances
      (project "data-center-rdimm-ddr4-tester"
        (path ""
          (reference "PS1") (unit 1)
        )
      )
    )
  )

  (symbol (lib_id "antmicroResistorsmisc:R_0R_0201") (at 363.22 113.03 180) (unit 1)
    (in_bom yes) (on_board yes) (dnp no)
    (property "Reference" "R106" (at 355.6 111.76 0)
      (effects (font (size 1.524 1.524)))
    )
    (property "Value" "R_0R_0201" (at 342.9 100.33 0)
      (effects (font (size 1.27 1.27) (thickness 0.15)) (justify left bottom) hide)
    )
    (property "Footprint" "antmicro-footprints:R_0201" (at 342.9 97.79 0)
      (effects (font (size 1.27 1.27) (thickness 0.15)) (justify left bottom) hide)
    )
    (property "Datasheet" "https://www.bourns.com/docs/product-datasheets/cr.pdf" (at 342.9 95.25 0)
      (effects (font (size 1.27 1.27) (thickness 0.15)) (justify left bottom) hide)
    )
    (property "Manufacturer" "Bourns" (at 342.9 90.17 0)
      (effects (font (size 1.27 1.27) (thickness 0.15)) (justify left bottom) hide)
    )
    (property "MPN" "CR0201-FX-0R00GLF" (at 342.9 92.71 0)
      (effects (font (size 1.27 1.27) (thickness 0.15)) (justify left bottom) hide)
    )
    (property "Val" "0R" (at 364.49 111.76 0)
      (effects (font (size 1.27 1.27) (thickness 0.15)))
    )
    (property "License" "Apache-2.0" (at 342.9 87.63 0)
      (effects (font (size 1.27 1.27) (thickness 0.15)) (justify left bottom) hide)
    )
    (property "Author" "Antmicro" (at 342.9 85.09 0)
      (effects (font (size 1.27 1.27) (thickness 0.15)) (justify left bottom) hide)
    )
    (property "Tolerance" "1%" (at 342.9 102.87 0)
      (effects (font (size 1.27 1.27)) (justify left bottom) hide)
    )
    (pin "1")
    (pin "2")
    (instances
      (project "data-center-rdimm-ddr4-tester"
        (path ""
          (reference "R106") (unit 1)
        )
      )
    )
  )

  (symbol (lib_id "antmicroResistors0402:R_24k9_0402") (at 234.315 207.645 90) (unit 1)
    (in_bom yes) (on_board yes) (dnp no) (fields_autoplaced)
    (property "Reference" "R175" (at 232.41 203.835 90)
      (effects (font (size 1.524 1.524)) (justify left))
    )
    (property "Value" "R_24k9_0402" (at 247.015 187.325 0)
      (effects (font (size 1.27 1.27) (thickness 0.15)) (justify left bottom) hide)
    )
    (property "Footprint" "antmicro-footprints:R_0402_1005Metric" (at 249.555 187.325 0)
      (effects (font (size 1.27 1.27) (thickness 0.15)) (justify left bottom) hide)
    )
    (property "Datasheet" "https://www.bourns.com/docs/product-datasheets/cr.pdf" (at 252.095 187.325 0)
      (effects (font (size 1.27 1.27) (thickness 0.15)) (justify left bottom) hide)
    )
    (property "Manufacturer" "Bourns" (at 257.175 187.325 0)
      (effects (font (size 1.27 1.27) (thickness 0.15)) (justify left bottom) hide)
    )
    (property "MPN" "CR0402-FX-2492GLF" (at 254.635 187.325 0)
      (effects (font (size 1.27 1.27) (thickness 0.15)) (justify left bottom) hide)
    )
    (property "Val" "24k9" (at 232.41 207.0099 90)
      (effects (font (size 1.27 1.27) (thickness 0.15)) (justify left))
    )
    (property "License" "Apache-2.0" (at 259.715 187.325 0)
      (effects (font (size 1.27 1.27) (thickness 0.15)) (justify left bottom) hide)
    )
    (property "Author" "Antmicro" (at 262.255 187.325 0)
      (effects (font (size 1.27 1.27) (thickness 0.15)) (justify left bottom) hide)
    )
    (property "Tolerance" "1%" (at 244.475 187.325 0)
      (effects (font (size 1.27 1.27)) (justify left bottom) hide)
    )
    (pin "1")
    (pin "2")
    (instances
      (project "data-center-rdimm-ddr4-tester"
        (path ""
          (reference "R175") (unit 1)
        )
      )
    )
  )

  (symbol (lib_id "antmicroResistors0402:R_0R_0402") (at 272.415 241.935 90) (unit 1)
    (in_bom no) (on_board yes) (dnp yes)
    (property "Reference" "R179" (at 274.32 238.125 90)
      (effects (font (size 1.524 1.524)) (justify right))
    )
    (property "Value" "R_0R_0402" (at 285.115 221.615 0)
      (effects (font (size 1.27 1.27) (thickness 0.15)) (justify left bottom) hide)
    )
    (property "Footprint" "antmicro-footprints:R_0402_1005Metric" (at 287.655 221.615 0)
      (effects (font (size 1.27 1.27) (thickness 0.15)) (justify left bottom) hide)
    )
    (property "Datasheet" "https://industrial.panasonic.com/cdbs/www-data/pdf/RDA0000/AOA0000C301.pdf" (at 290.195 221.615 0)
      (effects (font (size 1.27 1.27) (thickness 0.15)) (justify left bottom) hide)
    )
    (property "Manufacturer" "Panasonic" (at 295.275 221.615 0)
      (effects (font (size 1.27 1.27) (thickness 0.15)) (justify left bottom) hide)
    )
    (property "MPN" "ERJ2GE0R00X" (at 292.735 221.615 0)
      (effects (font (size 1.27 1.27) (thickness 0.15)) (justify left bottom) hide)
    )
    (property "Val" "0R" (at 274.32 241.2999 90)
      (effects (font (size 1.27 1.27) (thickness 0.15)) (justify right))
    )
    (property "License" "Apache-2.0" (at 297.815 221.615 0)
      (effects (font (size 1.27 1.27) (thickness 0.15)) (justify left bottom) hide)
    )
    (property "Author" "Antmicro" (at 300.355 221.615 0)
      (effects (font (size 1.27 1.27) (thickness 0.15)) (justify left bottom) hide)
    )
    (property "Tolerance" "~" (at 282.575 221.615 0)
      (effects (font (size 1.27 1.27)) (justify left bottom) hide)
    )
    (property "Current" "1A" (at 302.895 221.615 0)
      (effects (font (size 1.27 1.27) (thickness 0.15)) (justify left bottom) hide)
    )
    (property "DNP" "DNP" (at 272.415 239.395 0)
      (effects (font (size 1.27 1.27)))
    )
    (pin "1")
    (pin "2")
    (instances
      (project "data-center-rdimm-ddr4-tester"
        (path ""
          (reference "R179") (unit 1)
        )
      )
    )
  )

  (symbol (lib_id "antmicropower:GND") (at 334.01 238.76 0) (mirror y) (unit 1)
    (in_bom yes) (on_board yes) (dnp no) (fields_autoplaced)
    (property "Reference" "#PWR0314" (at 334.01 245.11 0)
      (effects (font (size 1.27 1.27)) hide)
    )
    (property "Value" "GND" (at 334.01 243.84 0)
      (effects (font (size 1.27 1.27)))
    )
    (property "Footprint" "" (at 334.01 238.76 0)
      (effects (font (size 1.27 1.27)) hide)
    )
    (property "Datasheet" "" (at 334.01 238.76 0)
      (effects (font (size 1.27 1.27)) hide)
    )
    (property "Author" "Antmicro" (at 325.12 246.38 0)
      (effects (font (size 1.27 1.27) (thickness 0.15)) (justify left bottom) hide)
    )
    (property "License" "Apache-2.0" (at 325.12 248.92 0)
      (effects (font (size 1.27 1.27) (thickness 0.15)) (justify left bottom) hide)
    )
    (pin "1")
    (instances
      (project "data-center-rdimm-ddr4-tester"
        (path ""
          (reference "#PWR0314") (unit 1)
        )
      )
    )
  )

  (symbol (lib_id "antmicropower:GNDD") (at 295.275 213.995 0) (unit 1)
    (in_bom yes) (on_board yes) (dnp no) (fields_autoplaced)
    (property "Reference" "#PWR0318" (at 295.275 220.345 0)
      (effects (font (size 1.27 1.27)) hide)
    )
    (property "Value" "GNDD" (at 295.275 219.075 0)
      (effects (font (size 1.27 1.27)))
    )
    (property "Footprint" "" (at 295.275 213.995 0)
      (effects (font (size 1.27 1.27)) hide)
    )
    (property "Datasheet" "" (at 295.275 213.995 0)
      (effects (font (size 1.27 1.27)) hide)
    )
    (property "Author" "Antmicro" (at 310.515 221.615 0)
      (effects (font (size 1.27 1.27) (thickness 0.15)) (justify left bottom) hide)
    )
    (property "License" "Apache-2.0" (at 310.515 224.155 0)
      (effects (font (size 1.27 1.27) (thickness 0.15)) (justify left bottom) hide)
    )
    (pin "1")
    (instances
      (project "data-center-rdimm-ddr4-tester"
        (path ""
          (reference "#PWR0318") (unit 1)
        )
      )
    )
  )

  (symbol (lib_id "antmicroResistors0402:R_10k_0402") (at 266.065 207.01 90) (unit 1)
    (in_bom no) (on_board yes) (dnp yes)
    (property "Reference" "R177" (at 266.7 201.295 90)
      (effects (font (size 1.524 1.524)) (justify right))
    )
    (property "Value" "R_10k_0402" (at 278.765 186.69 0)
      (effects (font (size 1.27 1.27) (thickness 0.15)) (justify left bottom) hide)
    )
    (property "Footprint" "antmicro-footprints:R_0402_1005Metric" (at 281.305 186.69 0)
      (effects (font (size 1.27 1.27) (thickness 0.15)) (justify left bottom) hide)
    )
    (property "Datasheet" "https://www.bourns.com/docs/product-datasheets/cr.pdf" (at 283.845 186.69 0)
      (effects (font (size 1.27 1.27) (thickness 0.15)) (justify left bottom) hide)
    )
    (property "Manufacturer" "Bourns" (at 288.925 186.69 0)
      (effects (font (size 1.27 1.27) (thickness 0.15)) (justify left bottom) hide)
    )
    (property "MPN" "CR0402-FX-1002GLF" (at 286.385 186.69 0)
      (effects (font (size 1.27 1.27) (thickness 0.15)) (justify left bottom) hide)
    )
    (property "Val" "10k" (at 266.7 207.645 90)
      (effects (font (size 1.27 1.27) (thickness 0.15)) (justify right))
    )
    (property "License" "Apache-2.0" (at 291.465 186.69 0)
      (effects (font (size 1.27 1.27) (thickness 0.15)) (justify left bottom) hide)
    )
    (property "Author" "Antmicro" (at 294.005 186.69 0)
      (effects (font (size 1.27 1.27) (thickness 0.15)) (justify left bottom) hide)
    )
    (property "Tolerance" "1%" (at 276.225 186.69 0)
      (effects (font (size 1.27 1.27)) (justify left bottom) hide)
    )
    (property "DNP" "DNP" (at 266.065 204.47 0)
      (effects (font (size 1.27 1.27)))
    )
    (pin "1")
    (pin "2")
    (instances
      (project "data-center-rdimm-ddr4-tester"
        (path ""
          (reference "R177") (unit 1)
        )
      )
    )
  )

  (symbol (lib_id "antmicroResistors0603:R_63R4_0603") (at 225.425 226.695 90) (unit 1)
    (in_bom yes) (on_board yes) (dnp no) (fields_autoplaced)
    (property "Reference" "R85" (at 223.52 222.885 90)
      (effects (font (size 1.524 1.524)) (justify left))
    )
    (property "Value" "R_63R4_0603" (at 238.125 206.375 0)
      (effects (font (size 1.27 1.27) (thickness 0.15)) (justify left bottom) hide)
    )
    (property "Footprint" "antmicro-footprints:R_0603_1608Metric" (at 240.665 206.375 0)
      (effects (font (size 1.27 1.27) (thickness 0.15)) (justify left bottom) hide)
    )
    (property "Datasheet" "https://www.bourns.com/docs/product-datasheets/cr.pdf" (at 243.205 206.375 0)
      (effects (font (size 1.27 1.27) (thickness 0.15)) (justify left bottom) hide)
    )
    (property "Manufacturer" "Bourns" (at 248.285 206.375 0)
      (effects (font (size 1.27 1.27) (thickness 0.15)) (justify left bottom) hide)
    )
    (property "MPN" "CR0603-FX-63R4ELF" (at 245.745 206.375 0)
      (effects (font (size 1.27 1.27) (thickness 0.15)) (justify left bottom) hide)
    )
    (property "Val" "63R4" (at 223.52 226.0599 90)
      (effects (font (size 1.27 1.27) (thickness 0.15)) (justify left))
    )
    (property "License" "Apache-2.0" (at 250.825 206.375 0)
      (effects (font (size 1.27 1.27) (thickness 0.15)) (justify left bottom) hide)
    )
    (property "Author" "Antmicro" (at 253.365 206.375 0)
      (effects (font (size 1.27 1.27) (thickness 0.15)) (justify left bottom) hide)
    )
    (property "Tolerance" "1%" (at 235.585 206.375 0)
      (effects (font (size 1.27 1.27)) (justify left bottom) hide)
    )
    (pin "1")
    (pin "2")
    (instances
      (project "data-center-rdimm-ddr4-tester"
        (path ""
          (reference "R85") (unit 1)
        )
      )
    )
  )

  (symbol (lib_id "antmicropower:GND") (at 332.74 94.615 0) (unit 1)
    (in_bom yes) (on_board yes) (dnp no) (fields_autoplaced)
    (property "Reference" "#PWR0325" (at 332.74 100.965 0)
      (effects (font (size 1.27 1.27)) hide)
    )
    (property "Value" "GND" (at 332.74 99.06 0)
      (effects (font (size 1.27 1.27)))
    )
    (property "Footprint" "" (at 332.74 94.615 0)
      (effects (font (size 1.27 1.27)) hide)
    )
    (property "Datasheet" "" (at 332.74 94.615 0)
      (effects (font (size 1.27 1.27)) hide)
    )
    (property "Author" "Antmicro" (at 341.63 102.235 0)
      (effects (font (size 1.27 1.27) (thickness 0.15)) (justify left bottom) hide)
    )
    (property "License" "Apache-2.0" (at 341.63 104.775 0)
      (effects (font (size 1.27 1.27) (thickness 0.15)) (justify left bottom) hide)
    )
    (pin "1")
    (instances
      (project "data-center-rdimm-ddr4-tester"
        (path ""
          (reference "#PWR0325") (unit 1)
        )
      )
    )
  )

  (symbol (lib_id "antmicropower:GNDD") (at 272.415 243.84 0) (unit 1)
    (in_bom yes) (on_board yes) (dnp no) (fields_autoplaced)
    (property "Reference" "#PWR015" (at 272.415 250.19 0)
      (effects (font (size 1.27 1.27)) hide)
    )
    (property "Value" "GNDD" (at 272.415 248.92 0)
      (effects (font (size 1.27 1.27)))
    )
    (property "Footprint" "" (at 272.415 243.84 0)
      (effects (font (size 1.27 1.27)) hide)
    )
    (property "Datasheet" "" (at 272.415 243.84 0)
      (effects (font (size 1.27 1.27)) hide)
    )
    (property "Author" "Antmicro" (at 287.655 251.46 0)
      (effects (font (size 1.27 1.27) (thickness 0.15)) (justify left bottom) hide)
    )
    (property "License" "Apache-2.0" (at 287.655 254 0)
      (effects (font (size 1.27 1.27) (thickness 0.15)) (justify left bottom) hide)
    )
    (pin "1")
    (instances
      (project "data-center-rdimm-ddr4-tester"
        (path ""
          (reference "#PWR015") (unit 1)
        )
      )
    )
  )

  (symbol (lib_id "antmicropower:GNDS") (at 78.74 244.475 0) (mirror y) (unit 1)
    (in_bom yes) (on_board yes) (dnp no) (fields_autoplaced)
    (property "Reference" "#PWR0396" (at 78.74 250.825 0)
      (effects (font (size 1.27 1.27)) hide)
    )
    (property "Value" "GNDS" (at 78.74 248.92 0)
      (effects (font (size 1.27 1.27)))
    )
    (property "Footprint" "" (at 78.74 244.475 0)
      (effects (font (size 1.27 1.27)) hide)
    )
    (property "Datasheet" "" (at 78.74 244.475 0)
      (effects (font (size 1.27 1.27)) hide)
    )
    (pin "1")
    (instances
      (project "data-center-rdimm-ddr4-tester"
        (path ""
          (reference "#PWR0396") (unit 1)
        )
      )
    )
  )

  (symbol (lib_id "antmicroResistors0402:R_10k_0402") (at 180.34 139.7 0) (unit 1)
    (in_bom yes) (on_board yes) (dnp no)
    (property "Reference" "R72" (at 178.435 138.43 0)
      (effects (font (size 1.524 1.524)))
    )
    (property "Value" "R_10k_0402" (at 200.66 152.4 0)
      (effects (font (size 1.27 1.27) (thickness 0.15)) (justify left bottom) hide)
    )
    (property "Footprint" "antmicro-footprints:R_0402_1005Metric" (at 200.66 154.94 0)
      (effects (font (size 1.27 1.27) (thickness 0.15)) (justify left bottom) hide)
    )
    (property "Datasheet" "https://www.bourns.com/docs/product-datasheets/cr.pdf" (at 200.66 157.48 0)
      (effects (font (size 1.27 1.27) (thickness 0.15)) (justify left bottom) hide)
    )
    (property "Manufacturer" "Bourns" (at 200.66 162.56 0)
      (effects (font (size 1.27 1.27) (thickness 0.15)) (justify left bottom) hide)
    )
    (property "MPN" "CR0402-FX-1002GLF" (at 200.66 160.02 0)
      (effects (font (size 1.27 1.27) (thickness 0.15)) (justify left bottom) hide)
    )
    (property "Val" "10k" (at 187.325 138.43 0)
      (effects (font (size 1.27 1.27) (thickness 0.15)))
    )
    (property "License" "Apache-2.0" (at 200.66 165.1 0)
      (effects (font (size 1.27 1.27) (thickness 0.15)) (justify left bottom) hide)
    )
    (property "Author" "Antmicro" (at 200.66 167.64 0)
      (effects (font (size 1.27 1.27) (thickness 0.15)) (justify left bottom) hide)
    )
    (property "Tolerance" "1%" (at 200.66 149.86 0)
      (effects (font (size 1.27 1.27)) (justify left bottom) hide)
    )
    (pin "1")
    (pin "2")
    (instances
      (project "data-center-rdimm-ddr4-tester"
        (path ""
          (reference "R72") (unit 1)
        )
      )
    )
  )

  (symbol (lib_id "data-center-rdimm-ddr4-tester:C_100n_16V_0402") (at 33.02 235.585 270) (unit 1)
    (in_bom yes) (on_board yes) (dnp no) (fields_autoplaced)
    (property "Reference" "C221" (at 29.845 236.8613 90)
      (effects (font (size 1.524 1.524)) (justify right))
    )
    (property "Value" "C_100n_16V_0402" (at 22.86 255.905 0)
      (effects (font (size 1.27 1.27) (thickness 0.15)) (justify left bottom) hide)
    )
    (property "Footprint" "data-center-rdimm-ddr4-tester-footprints:C_0402_1005Metric" (at 20.32 255.905 0)
      (effects (font (size 1.27 1.27) (thickness 0.15)) (justify left bottom) hide)
    )
    (property "Datasheet" " " (at 17.78 255.905 0)
      (effects (font (size 1.27 1.27) (thickness 0.15)) (justify left bottom) hide)
    )
    (property "Manufacturer" "Multicomp" (at 12.7 255.905 0)
      (effects (font (size 1.27 1.27) (thickness 0.15)) (justify left bottom) hide)
    )
    (property "MPN" "MC0402B104K160CT" (at 15.24 255.905 0)
      (effects (font (size 1.27 1.27) (thickness 0.15)) (justify left bottom) hide)
    )
    (property "Val" "100n" (at 29.845 240.0362 90)
      (effects (font (size 1.27 1.27) (thickness 0.15)) (justify right))
    )
    (property "License" "Apache-2.0" (at 10.16 255.905 0)
      (effects (font (size 1.27 1.27) (thickness 0.15)) (justify left bottom) hide)
    )
    (property "Author" "Antmicro" (at 7.62 255.905 0)
      (effects (font (size 1.27 1.27) (thickness 0.15)) (justify left bottom) hide)
    )
    (property "Voltage" "" (at 5.08 255.905 0)
      (effects (font (size 1.27 1.27)) (justify left bottom) hide)
    )
    (property "Dielectric" "" (at 2.54 255.905 0)
      (effects (font (size 1.27 1.27)) (justify left bottom) hide)
    )
    (pin "1")
    (pin "2")
    (instances
      (project "data-center-rdimm-ddr4-tester"
        (path ""
          (reference "C221") (unit 1)
        )
      )
    )
  )

  (symbol (lib_id "antmicroDiodesRectifiersSingle:PTVS58VS1UR,115") (at 200.025 215.265 90) (unit 1)
    (in_bom yes) (on_board yes) (dnp no) (fields_autoplaced)
    (property "Reference" "D14" (at 196.215 209.8675 90)
      (effects (font (size 1.524 1.524)) (justify left))
    )
    (property "Value" "PTVS58VS1UR,115" (at 196.215 213.0424 90)
      (effects (font (size 1.27 1.27) (thickness 0.15)) (justify left))
    )
    (property "Footprint" "antmicro-footprints:D_SOD-123F" (at 210.185 193.675 0)
      (effects (font (size 1.27 1.27) (thickness 0.15)) (justify left bottom) hide)
    )
    (property "Datasheet" "https://assets.nexperia.com/documents/data-sheet/PTVSXS1UR_SER.pdf" (at 212.725 193.675 0)
      (effects (font (size 1.27 1.27) (thickness 0.15)) (justify left bottom) hide)
    )
    (property "MPN" "PTVS58VS1UR,115" (at 215.265 193.675 0)
      (effects (font (size 1.27 1.27) (thickness 0.15)) (justify left bottom) hide)
    )
    (property "Manufacturer" "Nexperia" (at 217.805 193.675 0)
      (effects (font (size 1.27 1.27) (thickness 0.15)) (justify left bottom) hide)
    )
    (property "Author" "Antmicro" (at 220.345 193.675 0)
      (effects (font (size 1.27 1.27) (thickness 0.15)) (justify left bottom) hide)
    )
    (property "License" "Apache-2.0" (at 222.885 193.675 0)
      (effects (font (size 1.27 1.27) (thickness 0.15)) (justify left bottom) hide)
    )
    (pin "A")
    (pin "K")
    (instances
      (project "data-center-rdimm-ddr4-tester"
        (path ""
          (reference "D14") (unit 1)
        )
      )
    )
  )

  (symbol (lib_id "antmicroCapacitorsmisc:C_22u_100V_2220") (at 295.275 208.915 270) (unit 1)
    (in_bom yes) (on_board yes) (dnp no)
    (property "Reference" "C223" (at 294.005 204.47 0)
      (effects (font (size 1.524 1.524)) (justify left))
    )
    (property "Value" "C_22u_100V_2220" (at 285.115 229.235 0)
      (effects (font (size 1.27 1.27) (thickness 0.15)) (justify left bottom) hide)
    )
    (property "Footprint" "antmicro-footprints:C_2220_5650Metric" (at 282.575 229.235 0)
      (effects (font (size 1.27 1.27) (thickness 0.15)) (justify left bottom) hide)
    )
    (property "Datasheet" " " (at 280.035 229.235 0)
      (effects (font (size 1.27 1.27) (thickness 0.15)) (justify left bottom) hide)
    )
    (property "Manufacturer" "TDK" (at 274.955 229.235 0)
      (effects (font (size 1.27 1.27) (thickness 0.15)) (justify left bottom) hide)
    )
    (property "MPN" "C5750X7S2A226M280KB" (at 277.495 229.235 0)
      (effects (font (size 1.27 1.27) (thickness 0.15)) (justify left bottom) hide)
    )
    (property "Val" "22u/100V" (at 296.545 200.66 0)
      (effects (font (size 1.27 1.27) (thickness 0.15)) (justify left))
    )
    (property "License" "Apache-2.0" (at 272.415 229.235 0)
      (effects (font (size 1.27 1.27) (thickness 0.15)) (justify left bottom) hide)
    )
    (property "Author" "Antmicro" (at 269.875 229.235 0)
      (effects (font (size 1.27 1.27) (thickness 0.15)) (justify left bottom) hide)
    )
    (property "Voltage" "" (at 267.335 229.235 0)
      (effects (font (size 1.27 1.27)) (justify left bottom) hide)
    )
    (property "Dielectric" "" (at 264.795 229.235 0)
      (effects (font (size 1.27 1.27)) (justify left bottom) hide)
    )
    (pin "1")
    (pin "2")
    (instances
      (project "data-center-rdimm-ddr4-tester"
        (path ""
          (reference "C223") (unit 1)
        )
      )
    )
  )

  (symbol (lib_id "data-center-rdimm-ddr4-tester:C_100n_0805_100V") (at 205.105 208.915 270) (unit 1)
    (in_bom yes) (on_board yes) (dnp no) (fields_autoplaced)
    (property "Reference" "C222" (at 207.645 210.1913 90)
      (effects (font (size 1.524 1.524)) (justify left))
    )
    (property "Value" "C_100n_0805_100V" (at 194.945 229.235 0)
      (effects (font (size 1.27 1.27) (thickness 0.15)) (justify left bottom) hide)
    )
    (property "Footprint" "data-center-rdimm-ddr4-tester-footprints:C_0805_2012Metric" (at 192.405 229.235 0)
      (effects (font (size 1.27 1.27) (thickness 0.15)) (justify left bottom) hide)
    )
    (property "Datasheet" "https://www.mouser.pl/datasheet/2/585/MLCC-1837944.pdf" (at 189.865 229.235 0)
      (effects (font (size 1.27 1.27) (thickness 0.15)) (justify left bottom) hide)
    )
    (property "Manufacturer" "SAMSUNG" (at 184.785 229.235 0)
      (effects (font (size 1.27 1.27) (thickness 0.15)) (justify left bottom) hide)
    )
    (property "MPN" "CL21B104KCFNNNE" (at 187.325 229.235 0)
      (effects (font (size 1.27 1.27) (thickness 0.15)) (justify left bottom) hide)
    )
    (property "Val" "100n/100V" (at 207.645 213.3662 90)
      (effects (font (size 1.27 1.27) (thickness 0.15)) (justify left))
    )
    (property "License" "Apache-2.0" (at 182.245 229.235 0)
      (effects (font (size 1.27 1.27) (thickness 0.15)) (justify left bottom) hide)
    )
    (property "Author" "Antmicro" (at 179.705 229.235 0)
      (effects (font (size 1.27 1.27) (thickness 0.15)) (justify left bottom) hide)
    )
    (property "Voltage" "100V" (at 177.165 229.235 0)
      (effects (font (size 1.27 1.27)) (justify left bottom) hide)
    )
    (property "Dielectric" "X7R" (at 174.625 229.235 0)
      (effects (font (size 1.27 1.27)) (justify left bottom) hide)
    )
    (pin "1")
    (pin "2")
    (instances
      (project "data-center-rdimm-ddr4-tester"
        (path ""
          (reference "C222") (unit 1)
        )
      )
    )
  )

  (symbol (lib_id "data-center-rdimm-ddr4-tester:FB_220Z_2A_0603") (at 186.69 199.39 0) (unit 1)
    (in_bom yes) (on_board yes) (dnp no)
    (property "Reference" "FB9" (at 189.23 194.31 0)
      (effects (font (size 1.524 1.524)))
    )
    (property "Value" "FB_220Z_2A_0603" (at 189.1919 195.58 0)
      (effects (font (size 1.27 1.27) (thickness 0.15)) hide)
    )
    (property "Footprint" "data-center-rdimm-ddr4-tester-footprints:FB_0805_2012Metric" (at 200.66 204.47 0)
      (effects (font (size 1.27 1.27) (thickness 0.15)) (justify left bottom) hide)
    )
    (property "Datasheet" "https://www.murata.com/products/productdata/8796738977822/ENFA0005.pdf?1653276712000" (at 200.66 207.01 0)
      (effects (font (size 1.27 1.27) (thickness 0.15)) (justify left bottom) hide)
    )
    (property "MPN" "BLM21PG221SN1D" (at 189.23 196.215 0)
      (effects (font (size 1.27 1.27) (thickness 0.15)))
    )
    (property "Manufacturer" "Murata" (at 200.66 212.09 0)
      (effects (font (size 1.27 1.27) (thickness 0.15)) (justify left bottom) hide)
    )
    (property "Author" "Antmicro" (at 200.66 214.63 0)
      (effects (font (size 1.27 1.27) (thickness 0.15)) (justify left bottom) hide)
    )
    (property "License" "Apache-2.0" (at 200.66 217.17 0)
      (effects (font (size 1.27 1.27) (thickness 0.15)) (justify left bottom) hide)
    )
    (pin "1")
    (pin "2")
    (instances
      (project "data-center-rdimm-ddr4-tester"
        (path ""
          (reference "FB9") (unit 1)
        )
      )
    )
  )

  (symbol (lib_id "antmicroCapacitors0402:C_100n_0402") (at 335.28 160.02 270) (unit 1)
    (in_bom no) (on_board yes) (dnp yes)
    (property "Reference" "C288" (at 335.915 160.655 90)
      (effects (font (size 1.524 1.524)) (justify left))
    )
    (property "Value" "C_100n_0402" (at 325.12 180.34 0)
      (effects (font (size 1.27 1.27) (thickness 0.15)) (justify left bottom) hide)
    )
    (property "Footprint" "antmicro-footprints:C_0402_1005Metric" (at 322.58 180.34 0)
      (effects (font (size 1.27 1.27) (thickness 0.15)) (justify left bottom) hide)
    )
    (property "Datasheet" "https://search.murata.co.jp/Ceramy/image/img/A01X/G101/ENG/GRM155R61H104KE14-01.pdf" (at 320.04 180.34 0)
      (effects (font (size 1.27 1.27) (thickness 0.15)) (justify left bottom) hide)
    )
    (property "Manufacturer" "Murata" (at 314.96 180.34 0)
      (effects (font (size 1.27 1.27) (thickness 0.15)) (justify left bottom) hide)
    )
    (property "MPN" "GRM155R61H104KE14D" (at 317.5 180.34 0)
      (effects (font (size 1.27 1.27) (thickness 0.15)) (justify left bottom) hide)
    )
    (property "Val" "100n" (at 335.915 164.465 90)
      (effects (font (size 1.27 1.27) (thickness 0.15)) (justify left))
    )
    (property "License" "Apache-2.0" (at 312.42 180.34 0)
      (effects (font (size 1.27 1.27) (thickness 0.15)) (justify left bottom) hide)
    )
    (property "Author" "Antmicro" (at 309.88 180.34 0)
      (effects (font (size 1.27 1.27) (thickness 0.15)) (justify left bottom) hide)
    )
    (property "Voltage" "50V" (at 307.34 180.34 0)
      (effects (font (size 1.27 1.27)) (justify left bottom) hide)
    )
    (property "Dielectric" "X5R" (at 304.8 180.34 0)
      (effects (font (size 1.27 1.27)) (justify left bottom) hide)
    )
    (property "DNP" "DNP" (at 335.28 167.894 90)
      (effects (font (size 1.27 1.27)))
    )
    (pin "1")
    (pin "2")
    (instances
      (project "data-center-rdimm-ddr4-tester"
        (path ""
          (reference "C288") (unit 1)
        )
      )
    )
  )

  (symbol (lib_id "antmicroCapacitors0402:C_4u7_0402") (at 320.04 160.02 270) (unit 1)
    (in_bom no) (on_board yes) (dnp yes)
    (property "Reference" "C230" (at 320.675 160.655 90)
      (effects (font (size 1.524 1.524)) (justify left))
    )
    (property "Value" "C_4u7_0402" (at 309.88 180.34 0)
      (effects (font (size 1.27 1.27) (thickness 0.15)) (justify left bottom) hide)
    )
    (property "Footprint" "antmicro-footprints:C_0402_1005Metric" (at 307.34 180.34 0)
      (effects (font (size 1.27 1.27) (thickness 0.15)) (justify left bottom) hide)
    )
    (property "Datasheet" " " (at 304.8 180.34 0)
      (effects (font (size 1.27 1.27) (thickness 0.15)) (justify left bottom) hide)
    )
    (property "Manufacturer" "Murata" (at 299.72 180.34 0)
      (effects (font (size 1.27 1.27) (thickness 0.15)) (justify left bottom) hide)
    )
    (property "MPN" "GRM155R61A475MEAAD" (at 302.26 180.34 0)
      (effects (font (size 1.27 1.27) (thickness 0.15)) (justify left bottom) hide)
    )
    (property "Val" "4u7" (at 320.675 164.465 90)
      (effects (font (size 1.27 1.27) (thickness 0.15)) (justify left))
    )
    (property "License" "Apache-2.0" (at 297.18 180.34 0)
      (effects (font (size 1.27 1.27) (thickness 0.15)) (justify left bottom) hide)
    )
    (property "Author" "Antmicro" (at 294.64 180.34 0)
      (effects (font (size 1.27 1.27) (thickness 0.15)) (justify left bottom) hide)
    )
    (property "Voltage" "" (at 292.1 180.34 0)
      (effects (font (size 1.27 1.27)) (justify left bottom) hide)
    )
    (property "Dielectric" "" (at 289.56 180.34 0)
      (effects (font (size 1.27 1.27)) (justify left bottom) hide)
    )
    (property "DNP" "DNP" (at 317.754 164.719 90)
      (effects (font (size 1.27 1.27)))
    )
    (pin "1")
    (pin "2")
    (instances
      (project "data-center-rdimm-ddr4-tester"
        (path ""
          (reference "C230") (unit 1)
        )
      )
    )
  )

  (symbol (lib_id "antmicroResistorsmisc:R_0R_0201") (at 358.14 122.555 0) (unit 1)
    (in_bom yes) (on_board yes) (dnp no)
    (property "Reference" "R107" (at 355.6 121.285 0)
      (effects (font (size 1.524 1.524)))
    )
    (property "Value" "R_0R_0201" (at 378.46 135.255 0)
      (effects (font (size 1.27 1.27) (thickness 0.15)) (justify left bottom) hide)
    )
    (property "Footprint" "antmicro-footprints:R_0201" (at 378.46 137.795 0)
      (effects (font (size 1.27 1.27) (thickness 0.15)) (justify left bottom) hide)
    )
    (property "Datasheet" "https://www.bourns.com/docs/product-datasheets/cr.pdf" (at 378.46 140.335 0)
      (effects (font (size 1.27 1.27) (thickness 0.15)) (justify left bottom) hide)
    )
    (property "Manufacturer" "Bourns" (at 378.46 145.415 0)
      (effects (font (size 1.27 1.27) (thickness 0.15)) (justify left bottom) hide)
    )
    (property "MPN" "CR0201-FX-0R00GLF" (at 378.46 142.875 0)
      (effects (font (size 1.27 1.27) (thickness 0.15)) (justify left bottom) hide)
    )
    (property "Val" "0R" (at 364.49 121.285 0)
      (effects (font (size 1.27 1.27) (thickness 0.15)))
    )
    (property "License" "Apache-2.0" (at 378.46 147.955 0)
      (effects (font (size 1.27 1.27) (thickness 0.15)) (justify left bottom) hide)
    )
    (property "Author" "Antmicro" (at 378.46 150.495 0)
      (effects (font (size 1.27 1.27) (thickness 0.15)) (justify left bottom) hide)
    )
    (property "Tolerance" "1%" (at 378.46 132.715 0)
      (effects (font (size 1.27 1.27)) (justify left bottom) hide)
    )
    (pin "1")
    (pin "2")
    (instances
      (project "data-center-rdimm-ddr4-tester"
        (path ""
          (reference "R107") (unit 1)
        )
      )
    )
  )

  (symbol (lib_id "antmicroTVSDiodes:CD-MMBL110S") (at 156.21 194.31 0) (unit 1)
    (in_bom yes) (on_board yes) (dnp no)
    (property "Reference" "D12" (at 165.1 188.595 0)
      (effects (font (size 1.27 1.27)))
    )
    (property "Value" "CD-MMBL110S" (at 165.1 191.135 0)
      (effects (font (size 1.27 1.27) (thickness 0.15)))
    )
    (property "Footprint" "antmicro-footprints:DFN3538" (at 182.88 201.93 0)
      (effects (font (size 1.27 1.27) (thickness 0.15)) (justify left bottom) hide)
    )
    (property "Datasheet" "https://www.bourns.com/docs/product-datasheets/CD-MMBL110S.pdf" (at 182.88 204.47 0)
      (effects (font (size 1.27 1.27) (thickness 0.15)) (justify left bottom) hide)
    )
    (property "MPN" "CD-MMBL110S" (at 182.88 207.01 0)
      (effects (font (size 1.27 1.27) (thickness 0.15)) (justify left bottom) hide)
    )
    (property "Manufacturer" "Bourns" (at 182.88 209.55 0)
      (effects (font (size 1.27 1.27) (thickness 0.15)) (justify left bottom) hide)
    )
    (property "Author" "Antmicro" (at 182.88 212.09 0)
      (effects (font (size 1.27 1.27) (thickness 0.15)) (justify left bottom) hide)
    )
    (property "License" "Apache-2.0" (at 182.88 214.63 0)
      (effects (font (size 1.27 1.27) (thickness 0.15)) (justify left bottom) hide)
    )
    (pin "1")
    (pin "2")
    (pin "3")
    (pin "4")
    (instances
      (project "data-center-rdimm-ddr4-tester"
        (path ""
          (reference "D12") (unit 1)
        )
      )
    )
  )

  (symbol (lib_id "antmicroResistorsmisc:R_0R_0201") (at 337.185 125.095 180) (unit 1)
    (in_bom yes) (on_board yes) (dnp no)
    (property "Reference" "R100" (at 329.565 123.825 0)
      (effects (font (size 1.524 1.524)))
    )
    (property "Value" "R_0R_0201" (at 316.865 112.395 0)
      (effects (font (size 1.27 1.27) (thickness 0.15)) (justify left bottom) hide)
    )
    (property "Footprint" "antmicro-footprints:R_0201" (at 316.865 109.855 0)
      (effects (font (size 1.27 1.27) (thickness 0.15)) (justify left bottom) hide)
    )
    (property "Datasheet" "https://www.bourns.com/docs/product-datasheets/cr.pdf" (at 316.865 107.315 0)
      (effects (font (size 1.27 1.27) (thickness 0.15)) (justify left bottom) hide)
    )
    (property "Manufacturer" "Bourns" (at 316.865 102.235 0)
      (effects (font (size 1.27 1.27) (thickness 0.15)) (justify left bottom) hide)
    )
    (property "MPN" "CR0201-FX-0R00GLF" (at 316.865 104.775 0)
      (effects (font (size 1.27 1.27) (thickness 0.15)) (justify left bottom) hide)
    )
    (property "Val" "0R" (at 338.455 123.825 0)
      (effects (font (size 1.27 1.27) (thickness 0.15)))
    )
    (property "License" "Apache-2.0" (at 316.865 99.695 0)
      (effects (font (size 1.27 1.27) (thickness 0.15)) (justify left bottom) hide)
    )
    (property "Author" "Antmicro" (at 316.865 97.155 0)
      (effects (font (size 1.27 1.27) (thickness 0.15)) (justify left bottom) hide)
    )
    (property "Tolerance" "1%" (at 316.865 114.935 0)
      (effects (font (size 1.27 1.27)) (justify left bottom) hide)
    )
    (pin "1")
    (pin "2")
    (instances
      (project "data-center-rdimm-ddr4-tester"
        (path ""
          (reference "R100") (unit 1)
        )
      )
    )
  )

  (symbol (lib_id "antmicroCapacitors0402:C_100n_0402") (at 365.125 160.02 270) (unit 1)
    (in_bom no) (on_board yes) (dnp yes)
    (property "Reference" "C292" (at 365.76 160.655 90)
      (effects (font (size 1.524 1.524)) (justify left))
    )
    (property "Value" "C_100n_0402" (at 354.965 180.34 0)
      (effects (font (size 1.27 1.27) (thickness 0.15)) (justify left bottom) hide)
    )
    (property "Footprint" "antmicro-footprints:C_0402_1005Metric" (at 352.425 180.34 0)
      (effects (font (size 1.27 1.27) (thickness 0.15)) (justify left bottom) hide)
    )
    (property "Datasheet" "https://search.murata.co.jp/Ceramy/image/img/A01X/G101/ENG/GRM155R61H104KE14-01.pdf" (at 349.885 180.34 0)
      (effects (font (size 1.27 1.27) (thickness 0.15)) (justify left bottom) hide)
    )
    (property "Manufacturer" "Murata" (at 344.805 180.34 0)
      (effects (font (size 1.27 1.27) (thickness 0.15)) (justify left bottom) hide)
    )
    (property "MPN" "GRM155R61H104KE14D" (at 347.345 180.34 0)
      (effects (font (size 1.27 1.27) (thickness 0.15)) (justify left bottom) hide)
    )
    (property "Val" "100n" (at 365.76 164.465 90)
      (effects (font (size 1.27 1.27) (thickness 0.15)) (justify left))
    )
    (property "License" "Apache-2.0" (at 342.265 180.34 0)
      (effects (font (size 1.27 1.27) (thickness 0.15)) (justify left bottom) hide)
    )
    (property "Author" "Antmicro" (at 339.725 180.34 0)
      (effects (font (size 1.27 1.27) (thickness 0.15)) (justify left bottom) hide)
    )
    (property "Voltage" "50V" (at 337.185 180.34 0)
      (effects (font (size 1.27 1.27)) (justify left bottom) hide)
    )
    (property "Dielectric" "X5R" (at 334.645 180.34 0)
      (effects (font (size 1.27 1.27)) (justify left bottom) hide)
    )
    (property "DNP" "DNP" (at 365.125 167.894 90)
      (effects (font (size 1.27 1.27)))
    )
    (pin "1")
    (pin "2")
    (instances
      (project "data-center-rdimm-ddr4-tester"
        (path ""
          (reference "C292") (unit 1)
        )
      )
    )
  )

  (symbol (lib_id "antmicroResistorsmisc:R_0R_0201") (at 337.185 113.03 180) (unit 1)
    (in_bom yes) (on_board yes) (dnp no)
    (property "Reference" "R98" (at 330.2 111.76 0)
      (effects (font (size 1.524 1.524)))
    )
    (property "Value" "R_0R_0201" (at 316.865 100.33 0)
      (effects (font (size 1.27 1.27) (thickness 0.15)) (justify left bottom) hide)
    )
    (property "Footprint" "antmicro-footprints:R_0201" (at 316.865 97.79 0)
      (effects (font (size 1.27 1.27) (thickness 0.15)) (justify left bottom) hide)
    )
    (property "Datasheet" "https://www.bourns.com/docs/product-datasheets/cr.pdf" (at 316.865 95.25 0)
      (effects (font (size 1.27 1.27) (thickness 0.15)) (justify left bottom) hide)
    )
    (property "Manufacturer" "Bourns" (at 316.865 90.17 0)
      (effects (font (size 1.27 1.27) (thickness 0.15)) (justify left bottom) hide)
    )
    (property "MPN" "CR0201-FX-0R00GLF" (at 316.865 92.71 0)
      (effects (font (size 1.27 1.27) (thickness 0.15)) (justify left bottom) hide)
    )
    (property "Val" "0R" (at 338.455 111.76 0)
      (effects (font (size 1.27 1.27) (thickness 0.15)))
    )
    (property "License" "Apache-2.0" (at 316.865 87.63 0)
      (effects (font (size 1.27 1.27) (thickness 0.15)) (justify left bottom) hide)
    )
    (property "Author" "Antmicro" (at 316.865 85.09 0)
      (effects (font (size 1.27 1.27) (thickness 0.15)) (justify left bottom) hide)
    )
    (property "Tolerance" "1%" (at 316.865 102.87 0)
      (effects (font (size 1.27 1.27)) (justify left bottom) hide)
    )
    (pin "1")
    (pin "2")
    (instances
      (project "data-center-rdimm-ddr4-tester"
        (path ""
          (reference "R98") (unit 1)
        )
      )
    )
  )

  (symbol (lib_id "antmicroResistors0402:R_10k_0402") (at 180.34 160.02 0) (unit 1)
    (in_bom yes) (on_board yes) (dnp no)
    (property "Reference" "R79" (at 178.435 158.75 0)
      (effects (font (size 1.524 1.524)))
    )
    (property "Value" "R_10k_0402" (at 200.66 172.72 0)
      (effects (font (size 1.27 1.27) (thickness 0.15)) (justify left bottom) hide)
    )
    (property "Footprint" "antmicro-footprints:R_0402_1005Metric" (at 200.66 175.26 0)
      (effects (font (size 1.27 1.27) (thickness 0.15)) (justify left bottom) hide)
    )
    (property "Datasheet" "https://www.bourns.com/docs/product-datasheets/cr.pdf" (at 200.66 177.8 0)
      (effects (font (size 1.27 1.27) (thickness 0.15)) (justify left bottom) hide)
    )
    (property "Manufacturer" "Bourns" (at 200.66 182.88 0)
      (effects (font (size 1.27 1.27) (thickness 0.15)) (justify left bottom) hide)
    )
    (property "MPN" "CR0402-FX-1002GLF" (at 200.66 180.34 0)
      (effects (font (size 1.27 1.27) (thickness 0.15)) (justify left bottom) hide)
    )
    (property "Val" "10k" (at 187.325 158.75 0)
      (effects (font (size 1.27 1.27) (thickness 0.15)))
    )
    (property "License" "Apache-2.0" (at 200.66 185.42 0)
      (effects (font (size 1.27 1.27) (thickness 0.15)) (justify left bottom) hide)
    )
    (property "Author" "Antmicro" (at 200.66 187.96 0)
      (effects (font (size 1.27 1.27) (thickness 0.15)) (justify left bottom) hide)
    )
    (property "Tolerance" "1%" (at 200.66 170.18 0)
      (effects (font (size 1.27 1.27)) (justify left bottom) hide)
    )
    (pin "1")
    (pin "2")
    (instances
      (project "data-center-rdimm-ddr4-tester"
        (path ""
          (reference "R79") (unit 1)
        )
      )
    )
  )

  (symbol (lib_id "antmicroResistors0402:R_0R_0402") (at 220.345 237.49 0) (unit 1)
    (in_bom yes) (on_board yes) (dnp no)
    (property "Reference" "R161" (at 217.805 236.22 0)
      (effects (font (size 1.524 1.524)))
    )
    (property "Value" "R_0R_0402" (at 240.665 250.19 0)
      (effects (font (size 1.27 1.27) (thickness 0.15)) (justify left bottom) hide)
    )
    (property "Footprint" "antmicro-footprints:R_0402_1005Metric" (at 240.665 252.73 0)
      (effects (font (size 1.27 1.27) (thickness 0.15)) (justify left bottom) hide)
    )
    (property "Datasheet" "https://industrial.panasonic.com/cdbs/www-data/pdf/RDA0000/AOA0000C301.pdf" (at 240.665 255.27 0)
      (effects (font (size 1.27 1.27) (thickness 0.15)) (justify left bottom) hide)
    )
    (property "Manufacturer" "Panasonic" (at 240.665 260.35 0)
      (effects (font (size 1.27 1.27) (thickness 0.15)) (justify left bottom) hide)
    )
    (property "MPN" "ERJ2GE0R00X" (at 240.665 257.81 0)
      (effects (font (size 1.27 1.27) (thickness 0.15)) (justify left bottom) hide)
    )
    (property "Val" "0R" (at 227.33 236.22 0)
      (effects (font (size 1.27 1.27) (thickness 0.15)))
    )
    (property "License" "Apache-2.0" (at 240.665 262.89 0)
      (effects (font (size 1.27 1.27) (thickness 0.15)) (justify left bottom) hide)
    )
    (property "Author" "Antmicro" (at 240.665 265.43 0)
      (effects (font (size 1.27 1.27) (thickness 0.15)) (justify left bottom) hide)
    )
    (property "Tolerance" "~" (at 240.665 247.65 0)
      (effects (font (size 1.27 1.27)) (justify left bottom) hide)
    )
    (property "Current" "1A" (at 240.665 267.97 0)
      (effects (font (size 1.27 1.27) (thickness 0.15)) (justify left bottom) hide)
    )
    (pin "1")
    (pin "2")
    (instances
      (project "data-center-rdimm-ddr4-tester"
        (path ""
          (reference "R161") (unit 1)
        )
      )
    )
  )

  (symbol (lib_id "antmicroResistors0603:R_1k_0603") (at 344.17 237.49 0) (mirror y) (unit 1)
    (in_bom yes) (on_board yes) (dnp no)
    (property "Reference" "R184" (at 336.55 236.22 0)
      (effects (font (size 1.524 1.524)))
    )
    (property "Value" "R_1k_0603" (at 323.85 250.19 0)
      (effects (font (size 1.27 1.27) (thickness 0.15)) (justify left bottom) hide)
    )
    (property "Footprint" "antmicro-footprints:R_0603_1608Metric" (at 323.85 252.73 0)
      (effects (font (size 1.27 1.27) (thickness 0.15)) (justify left bottom) hide)
    )
    (property "Datasheet" "https://www.bourns.com/docs/product-datasheets/cr.pdf" (at 323.85 255.27 0)
      (effects (font (size 1.27 1.27) (thickness 0.15)) (justify left bottom) hide)
    )
    (property "Manufacturer" "Bourns" (at 323.85 260.35 0)
      (effects (font (size 1.27 1.27) (thickness 0.15)) (justify left bottom) hide)
    )
    (property "MPN" "CR0603-FX-1001ELF" (at 323.85 257.81 0)
      (effects (font (size 1.27 1.27) (thickness 0.15)) (justify left bottom) hide)
    )
    (property "Val" "1k" (at 345.44 236.22 0)
      (effects (font (size 1.27 1.27) (thickness 0.15)))
    )
    (property "License" "Apache-2.0" (at 323.85 262.89 0)
      (effects (font (size 1.27 1.27) (thickness 0.15)) (justify left bottom) hide)
    )
    (property "Author" "Antmicro" (at 323.85 265.43 0)
      (effects (font (size 1.27 1.27) (thickness 0.15)) (justify left bottom) hide)
    )
    (property "Tolerance" "1%" (at 323.85 247.65 0)
      (effects (font (size 1.27 1.27)) (justify left bottom) hide)
    )
    (pin "1")
    (pin "2")
    (instances
      (project "data-center-rdimm-ddr4-tester"
        (path ""
          (reference "R184") (unit 1)
        )
      )
    )
  )

  (symbol (lib_id "antmicroResistorsmisc:R_0R_0201") (at 358.14 144.78 0) (unit 1)
    (in_bom yes) (on_board yes) (dnp no)
    (property "Reference" "R111" (at 355.6 143.51 0)
      (effects (font (size 1.524 1.524)))
    )
    (property "Value" "R_0R_0201" (at 378.46 157.48 0)
      (effects (font (size 1.27 1.27) (thickness 0.15)) (justify left bottom) hide)
    )
    (property "Footprint" "antmicro-footprints:R_0201" (at 378.46 160.02 0)
      (effects (font (size 1.27 1.27) (thickness 0.15)) (justify left bottom) hide)
    )
    (property "Datasheet" "https://www.bourns.com/docs/product-datasheets/cr.pdf" (at 378.46 162.56 0)
      (effects (font (size 1.27 1.27) (thickness 0.15)) (justify left bottom) hide)
    )
    (property "Manufacturer" "Bourns" (at 378.46 167.64 0)
      (effects (font (size 1.27 1.27) (thickness 0.15)) (justify left bottom) hide)
    )
    (property "MPN" "CR0201-FX-0R00GLF" (at 378.46 165.1 0)
      (effects (font (size 1.27 1.27) (thickness 0.15)) (justify left bottom) hide)
    )
    (property "Val" "0R" (at 364.49 143.51 0)
      (effects (font (size 1.27 1.27) (thickness 0.15)))
    )
    (property "License" "Apache-2.0" (at 378.46 170.18 0)
      (effects (font (size 1.27 1.27) (thickness 0.15)) (justify left bottom) hide)
    )
    (property "Author" "Antmicro" (at 378.46 172.72 0)
      (effects (font (size 1.27 1.27) (thickness 0.15)) (justify left bottom) hide)
    )
    (property "Tolerance" "1%" (at 378.46 154.94 0)
      (effects (font (size 1.27 1.27)) (justify left bottom) hide)
    )
    (pin "1")
    (pin "2")
    (instances
      (project "data-center-rdimm-ddr4-tester"
        (path ""
          (reference "R111") (unit 1)
        )
      )
    )
  )

  (symbol (lib_id "antmicroResistors0402:R_10k_0402") (at 180.34 147.32 0) (unit 1)
    (in_bom no) (on_board yes) (dnp yes)
    (property "Reference" "R75" (at 178.435 146.05 0)
      (effects (font (size 1.524 1.524)))
    )
    (property "Value" "R_10k_0402" (at 200.66 160.02 0)
      (effects (font (size 1.27 1.27) (thickness 0.15)) (justify left bottom) hide)
    )
    (property "Footprint" "antmicro-footprints:R_0402_1005Metric" (at 200.66 162.56 0)
      (effects (font (size 1.27 1.27) (thickness 0.15)) (justify left bottom) hide)
    )
    (property "Datasheet" "https://www.bourns.com/docs/product-datasheets/cr.pdf" (at 200.66 165.1 0)
      (effects (font (size 1.27 1.27) (thickness 0.15)) (justify left bottom) hide)
    )
    (property "Manufacturer" "Bourns" (at 200.66 170.18 0)
      (effects (font (size 1.27 1.27) (thickness 0.15)) (justify left bottom) hide)
    )
    (property "MPN" "CR0402-FX-1002GLF" (at 200.66 167.64 0)
      (effects (font (size 1.27 1.27) (thickness 0.15)) (justify left bottom) hide)
    )
    (property "Val" "10k" (at 187.325 146.05 0)
      (effects (font (size 1.27 1.27) (thickness 0.15)))
    )
    (property "License" "Apache-2.0" (at 200.66 172.72 0)
      (effects (font (size 1.27 1.27) (thickness 0.15)) (justify left bottom) hide)
    )
    (property "Author" "Antmicro" (at 200.66 175.26 0)
      (effects (font (size 1.27 1.27) (thickness 0.15)) (justify left bottom) hide)
    )
    (property "Tolerance" "1%" (at 200.66 157.48 0)
      (effects (font (size 1.27 1.27)) (justify left bottom) hide)
    )
    (property "DNP" "DNP" (at 182.88 147.32 0)
      (effects (font (size 1.27 1.27)))
    )
    (pin "1")
    (pin "2")
    (instances
      (project "data-center-rdimm-ddr4-tester"
        (path ""
          (reference "R75") (unit 1)
        )
      )
    )
  )

  (symbol (lib_id "antmicroCapacitorsmisc:C_22u_100V_2220") (at 302.26 208.915 270) (unit 1)
    (in_bom yes) (on_board yes) (dnp no)
    (property "Reference" "C224" (at 300.99 204.47 0)
      (effects (font (size 1.524 1.524)) (justify left))
    )
    (property "Value" "C_22u_100V_2220" (at 292.1 229.235 0)
      (effects (font (size 1.27 1.27) (thickness 0.15)) (justify left bottom) hide)
    )
    (property "Footprint" "antmicro-footprints:C_2220_5650Metric" (at 289.56 229.235 0)
      (effects (font (size 1.27 1.27) (thickness 0.15)) (justify left bottom) hide)
    )
    (property "Datasheet" " " (at 287.02 229.235 0)
      (effects (font (size 1.27 1.27) (thickness 0.15)) (justify left bottom) hide)
    )
    (property "Manufacturer" "TDK" (at 281.94 229.235 0)
      (effects (font (size 1.27 1.27) (thickness 0.15)) (justify left bottom) hide)
    )
    (property "MPN" "C5750X7S2A226M280KB" (at 284.48 229.235 0)
      (effects (font (size 1.27 1.27) (thickness 0.15)) (justify left bottom) hide)
    )
    (property "Val" "22u/100V" (at 303.53 200.66 0)
      (effects (font (size 1.27 1.27) (thickness 0.15)) (justify left))
    )
    (property "License" "Apache-2.0" (at 279.4 229.235 0)
      (effects (font (size 1.27 1.27) (thickness 0.15)) (justify left bottom) hide)
    )
    (property "Author" "Antmicro" (at 276.86 229.235 0)
      (effects (font (size 1.27 1.27) (thickness 0.15)) (justify left bottom) hide)
    )
    (property "Voltage" "" (at 274.32 229.235 0)
      (effects (font (size 1.27 1.27)) (justify left bottom) hide)
    )
    (property "Dielectric" "" (at 271.78 229.235 0)
      (effects (font (size 1.27 1.27)) (justify left bottom) hide)
    )
    (pin "1")
    (pin "2")
    (instances
      (project "data-center-rdimm-ddr4-tester"
        (path ""
          (reference "C224") (unit 1)
        )
      )
    )
  )

  (symbol (lib_id "antmicropower:GND") (at 320.04 167.64 0) (unit 1)
    (in_bom yes) (on_board yes) (dnp no) (fields_autoplaced)
    (property "Reference" "#PWR0326" (at 320.04 173.99 0)
      (effects (font (size 1.27 1.27)) hide)
    )
    (property "Value" "GND" (at 320.04 172.085 0)
      (effects (font (size 1.27 1.27)))
    )
    (property "Footprint" "" (at 320.04 167.64 0)
      (effects (font (size 1.27 1.27)) hide)
    )
    (property "Datasheet" "" (at 320.04 167.64 0)
      (effects (font (size 1.27 1.27)) hide)
    )
    (property "Author" "Antmicro" (at 328.93 175.26 0)
      (effects (font (size 1.27 1.27) (thickness 0.15)) (justify left bottom) hide)
    )
    (property "License" "Apache-2.0" (at 328.93 177.8 0)
      (effects (font (size 1.27 1.27) (thickness 0.15)) (justify left bottom) hide)
    )
    (pin "1")
    (instances
      (project "data-center-rdimm-ddr4-tester"
        (path ""
          (reference "#PWR0326") (unit 1)
        )
      )
    )
  )

  (symbol (lib_id "antmicroResistors0402:R_10k_0402") (at 180.34 134.62 0) (unit 1)
    (in_bom no) (on_board yes) (dnp yes)
    (property "Reference" "R70" (at 178.435 133.35 0)
      (effects (font (size 1.524 1.524)))
    )
    (property "Value" "R_10k_0402" (at 200.66 147.32 0)
      (effects (font (size 1.27 1.27) (thickness 0.15)) (justify left bottom) hide)
    )
    (property "Footprint" "antmicro-footprints:R_0402_1005Metric" (at 200.66 149.86 0)
      (effects (font (size 1.27 1.27) (thickness 0.15)) (justify left bottom) hide)
    )
    (property "Datasheet" "https://www.bourns.com/docs/product-datasheets/cr.pdf" (at 200.66 152.4 0)
      (effects (font (size 1.27 1.27) (thickness 0.15)) (justify left bottom) hide)
    )
    (property "Manufacturer" "Bourns" (at 200.66 157.48 0)
      (effects (font (size 1.27 1.27) (thickness 0.15)) (justify left bottom) hide)
    )
    (property "MPN" "CR0402-FX-1002GLF" (at 200.66 154.94 0)
      (effects (font (size 1.27 1.27) (thickness 0.15)) (justify left bottom) hide)
    )
    (property "Val" "10k" (at 187.325 133.35 0)
      (effects (font (size 1.27 1.27) (thickness 0.15)))
    )
    (property "License" "Apache-2.0" (at 200.66 160.02 0)
      (effects (font (size 1.27 1.27) (thickness 0.15)) (justify left bottom) hide)
    )
    (property "Author" "Antmicro" (at 200.66 162.56 0)
      (effects (font (size 1.27 1.27) (thickness 0.15)) (justify left bottom) hide)
    )
    (property "Tolerance" "1%" (at 200.66 144.78 0)
      (effects (font (size 1.27 1.27)) (justify left bottom) hide)
    )
    (property "DNP" "DNP" (at 182.88 134.62 0)
      (effects (font (size 1.27 1.27)))
    )
    (pin "1")
    (pin "2")
    (instances
      (project "data-center-rdimm-ddr4-tester"
        (path ""
          (reference "R70") (unit 1)
        )
      )
    )
  )

  (symbol (lib_id "antmicroResistors0603:R_1k_0603") (at 369.57 237.49 0) (mirror y) (unit 1)
    (in_bom yes) (on_board yes) (dnp no)
    (property "Reference" "R183" (at 361.95 236.22 0)
      (effects (font (size 1.524 1.524)))
    )
    (property "Value" "R_1k_0603" (at 349.25 250.19 0)
      (effects (font (size 1.27 1.27) (thickness 0.15)) (justify left bottom) hide)
    )
    (property "Footprint" "antmicro-footprints:R_0603_1608Metric" (at 349.25 252.73 0)
      (effects (font (size 1.27 1.27) (thickness 0.15)) (justify left bottom) hide)
    )
    (property "Datasheet" "https://www.bourns.com/docs/product-datasheets/cr.pdf" (at 349.25 255.27 0)
      (effects (font (size 1.27 1.27) (thickness 0.15)) (justify left bottom) hide)
    )
    (property "Manufacturer" "Bourns" (at 349.25 260.35 0)
      (effects (font (size 1.27 1.27) (thickness 0.15)) (justify left bottom) hide)
    )
    (property "MPN" "CR0603-FX-1001ELF" (at 349.25 257.81 0)
      (effects (font (size 1.27 1.27) (thickness 0.15)) (justify left bottom) hide)
    )
    (property "Val" "1k" (at 370.205 236.22 0)
      (effects (font (size 1.27 1.27) (thickness 0.15)))
    )
    (property "License" "Apache-2.0" (at 349.25 262.89 0)
      (effects (font (size 1.27 1.27) (thickness 0.15)) (justify left bottom) hide)
    )
    (property "Author" "Antmicro" (at 349.25 265.43 0)
      (effects (font (size 1.27 1.27) (thickness 0.15)) (justify left bottom) hide)
    )
    (property "Tolerance" "1%" (at 349.25 247.65 0)
      (effects (font (size 1.27 1.27)) (justify left bottom) hide)
    )
    (pin "1")
    (pin "2")
    (instances
      (project "data-center-rdimm-ddr4-tester"
        (path ""
          (reference "R183") (unit 1)
        )
      )
    )
  )

  (symbol (lib_id "antmicroResistors0402:R_10k_0402") (at 180.34 152.4 0) (unit 1)
    (in_bom yes) (on_board yes) (dnp no)
    (property "Reference" "R80" (at 178.435 151.13 0)
      (effects (font (size 1.524 1.524)))
    )
    (property "Value" "R_10k_0402" (at 200.66 165.1 0)
      (effects (font (size 1.27 1.27) (thickness 0.15)) (justify left bottom) hide)
    )
    (property "Footprint" "antmicro-footprints:R_0402_1005Metric" (at 200.66 167.64 0)
      (effects (font (size 1.27 1.27) (thickness 0.15)) (justify left bottom) hide)
    )
    (property "Datasheet" "https://www.bourns.com/docs/product-datasheets/cr.pdf" (at 200.66 170.18 0)
      (effects (font (size 1.27 1.27) (thickness 0.15)) (justify left bottom) hide)
    )
    (property "Manufacturer" "Bourns" (at 200.66 175.26 0)
      (effects (font (size 1.27 1.27) (thickness 0.15)) (justify left bottom) hide)
    )
    (property "MPN" "CR0402-FX-1002GLF" (at 200.66 172.72 0)
      (effects (font (size 1.27 1.27) (thickness 0.15)) (justify left bottom) hide)
    )
    (property "Val" "10k" (at 187.325 151.13 0)
      (effects (font (size 1.27 1.27) (thickness 0.15)))
    )
    (property "License" "Apache-2.0" (at 200.66 177.8 0)
      (effects (font (size 1.27 1.27) (thickness 0.15)) (justify left bottom) hide)
    )
    (property "Author" "Antmicro" (at 200.66 180.34 0)
      (effects (font (size 1.27 1.27) (thickness 0.15)) (justify left bottom) hide)
    )
    (property "Tolerance" "1%" (at 200.66 162.56 0)
      (effects (font (size 1.27 1.27)) (justify left bottom) hide)
    )
    (pin "1")
    (pin "2")
    (instances
      (project "data-center-rdimm-ddr4-tester"
        (path ""
          (reference "R80") (unit 1)
        )
      )
    )
  )

  (symbol (lib_id "antmicropower:GNDD") (at 318.135 213.995 0) (unit 1)
    (in_bom yes) (on_board yes) (dnp no) (fields_autoplaced)
    (property "Reference" "#PWR0319" (at 318.135 220.345 0)
      (effects (font (size 1.27 1.27)) hide)
    )
    (property "Value" "GNDD" (at 318.135 218.44 0)
      (effects (font (size 1.27 1.27)))
    )
    (property "Footprint" "" (at 318.135 213.995 0)
      (effects (font (size 1.27 1.27)) hide)
    )
    (property "Datasheet" "" (at 318.135 213.995 0)
      (effects (font (size 1.27 1.27)) hide)
    )
    (property "Author" "Antmicro" (at 333.375 221.615 0)
      (effects (font (size 1.27 1.27) (thickness 0.15)) (justify left bottom) hide)
    )
    (property "License" "Apache-2.0" (at 333.375 224.155 0)
      (effects (font (size 1.27 1.27) (thickness 0.15)) (justify left bottom) hide)
    )
    (pin "1")
    (instances
      (project "data-center-rdimm-ddr4-tester"
        (path ""
          (reference "#PWR0319") (unit 1)
        )
      )
    )
  )

  (symbol (lib_id "data-center-rdimm-ddr4-tester:FB_220Z_2A_0603") (at 187.325 229.87 0) (unit 1)
    (in_bom yes) (on_board yes) (dnp no)
    (property "Reference" "FB10" (at 189.865 224.79 0)
      (effects (font (size 1.524 1.524)))
    )
    (property "Value" "FB_220Z_2A_0603" (at 189.8269 226.06 0)
      (effects (font (size 1.27 1.27) (thickness 0.15)) hide)
    )
    (property "Footprint" "data-center-rdimm-ddr4-tester-footprints:FB_0805_2012Metric" (at 201.295 234.95 0)
      (effects (font (size 1.27 1.27) (thickness 0.15)) (justify left bottom) hide)
    )
    (property "Datasheet" "https://www.murata.com/products/productdata/8796738977822/ENFA0005.pdf?1653276712000" (at 201.295 237.49 0)
      (effects (font (size 1.27 1.27) (thickness 0.15)) (justify left bottom) hide)
    )
    (property "MPN" "BLM21PG221SN1D" (at 189.865 226.695 0)
      (effects (font (size 1.27 1.27) (thickness 0.15)))
    )
    (property "Manufacturer" "Murata" (at 201.295 242.57 0)
      (effects (font (size 1.27 1.27) (thickness 0.15)) (justify left bottom) hide)
    )
    (property "Author" "Antmicro" (at 201.295 245.11 0)
      (effects (font (size 1.27 1.27) (thickness 0.15)) (justify left bottom) hide)
    )
    (property "License" "Apache-2.0" (at 201.295 247.65 0)
      (effects (font (size 1.27 1.27) (thickness 0.15)) (justify left bottom) hide)
    )
    (pin "1")
    (pin "2")
    (instances
      (project "data-center-rdimm-ddr4-tester"
        (path ""
          (reference "FB10") (unit 1)
        )
      )
    )
  )

  (symbol (lib_id "antmicroResistorsmisc:R_0R_0201") (at 358.14 110.49 0) (unit 1)
    (in_bom yes) (on_board yes) (dnp no)
    (property "Reference" "R105" (at 355.6 109.22 0)
      (effects (font (size 1.524 1.524)))
    )
    (property "Value" "R_0R_0201" (at 378.46 123.19 0)
      (effects (font (size 1.27 1.27) (thickness 0.15)) (justify left bottom) hide)
    )
    (property "Footprint" "antmicro-footprints:R_0201" (at 378.46 125.73 0)
      (effects (font (size 1.27 1.27) (thickness 0.15)) (justify left bottom) hide)
    )
    (property "Datasheet" "https://www.bourns.com/docs/product-datasheets/cr.pdf" (at 378.46 128.27 0)
      (effects (font (size 1.27 1.27) (thickness 0.15)) (justify left bottom) hide)
    )
    (property "Manufacturer" "Bourns" (at 378.46 133.35 0)
      (effects (font (size 1.27 1.27) (thickness 0.15)) (justify left bottom) hide)
    )
    (property "MPN" "CR0201-FX-0R00GLF" (at 378.46 130.81 0)
      (effects (font (size 1.27 1.27) (thickness 0.15)) (justify left bottom) hide)
    )
    (property "Val" "0R" (at 364.49 109.22 0)
      (effects (font (size 1.27 1.27) (thickness 0.15)))
    )
    (property "License" "Apache-2.0" (at 378.46 135.89 0)
      (effects (font (size 1.27 1.27) (thickness 0.15)) (justify left bottom) hide)
    )
    (property "Author" "Antmicro" (at 378.46 138.43 0)
      (effects (font (size 1.27 1.27) (thickness 0.15)) (justify left bottom) hide)
    )
    (property "Tolerance" "1%" (at 378.46 120.65 0)
      (effects (font (size 1.27 1.27)) (justify left bottom) hide)
    )
    (pin "1")
    (pin "2")
    (instances
      (project "data-center-rdimm-ddr4-tester"
        (path ""
          (reference "R105") (unit 1)
        )
      )
    )
  )

  (symbol (lib_id "antmicroResistors0402:R_0R_0402") (at 312.42 33.02 0) (unit 1)
    (in_bom no) (on_board yes) (dnp yes)
    (property "Reference" "R206" (at 309.88 31.75 0)
      (effects (font (size 1.524 1.524)))
    )
    (property "Value" "R_0R_0402" (at 332.74 45.72 0)
      (effects (font (size 1.27 1.27) (thickness 0.15)) (justify left bottom) hide)
    )
    (property "Footprint" "antmicro-footprints:R_0402_1005Metric" (at 332.74 48.26 0)
      (effects (font (size 1.27 1.27) (thickness 0.15)) (justify left bottom) hide)
    )
    (property "Datasheet" "https://industrial.panasonic.com/cdbs/www-data/pdf/RDA0000/AOA0000C301.pdf" (at 332.74 50.8 0)
      (effects (font (size 1.27 1.27) (thickness 0.15)) (justify left bottom) hide)
    )
    (property "Manufacturer" "Panasonic" (at 332.74 55.88 0)
      (effects (font (size 1.27 1.27) (thickness 0.15)) (justify left bottom) hide)
    )
    (property "MPN" "ERJ2GE0R00X" (at 332.74 53.34 0)
      (effects (font (size 1.27 1.27) (thickness 0.15)) (justify left bottom) hide)
    )
    (property "Val" "0R" (at 318.77 31.75 0)
      (effects (font (size 1.27 1.27) (thickness 0.15)))
    )
    (property "License" "Apache-2.0" (at 332.74 58.42 0)
      (effects (font (size 1.27 1.27) (thickness 0.15)) (justify left bottom) hide)
    )
    (property "Author" "Antmicro" (at 332.74 60.96 0)
      (effects (font (size 1.27 1.27) (thickness 0.15)) (justify left bottom) hide)
    )
    (property "Tolerance" "~" (at 332.74 43.18 0)
      (effects (font (size 1.27 1.27)) (justify left bottom) hide)
    )
    (property "Current" "1A" (at 332.74 63.5 0)
      (effects (font (size 1.27 1.27) (thickness 0.15)) (justify left bottom) hide)
    )
    (property "DNP" "DNP" (at 314.96 33.02 0)
      (effects (font (size 1.27 1.27)))
    )
    (pin "1")
    (pin "2")
    (instances
      (project "data-center-rdimm-ddr4-tester"
        (path ""
          (reference "R206") (unit 1)
        )
      )
    )
  )

  (symbol (lib_id "antmicroModularConnectorsJacksWithMagnetics:Bus_RJ45_5-2337992-8") (at 55.88 207.01 0) (unit 1)
    (in_bom yes) (on_board yes) (dnp no)
    (property "Reference" "J2" (at 66.675 200.025 0)
      (effects (font (size 1.524 1.524)))
    )
    (property "Value" "Bus_RJ45_5-2337992-8" (at 91.44 212.09 0)
      (effects (font (size 1.27 1.27) (thickness 0.15)) (justify left bottom) hide)
    )
    (property "Footprint" "antmicro-footprints:RJ45_5-2337992-8_Horizontal" (at 91.44 214.63 0)
      (effects (font (size 1.27 1.27) (thickness 0.15)) (justify left bottom) hide)
    )
    (property "Datasheet" "https://www.te.com/commerce/DocumentDelivery/DDEController?Action=showdoc&DocId=Customer+Drawing%7F5-2337992-8%7FA%7Fpdf%7FEnglish%7FENG_CD_5-2337992-8_A.pdf%7F5-2337992-8" (at 91.44 217.17 0)
      (effects (font (size 1.27 1.27) (thickness 0.15)) (justify left bottom) hide)
    )
    (property "MPN" "5-2337992-8" (at 66.675 202.565 0)
      (effects (font (size 1.27 1.27) (thickness 0.15)))
    )
    (property "Manufacturer" "TE Connectivity" (at 91.44 222.25 0)
      (effects (font (size 1.27 1.27) (thickness 0.15)) (justify left bottom) hide)
    )
    (property "Author" "Antmicro" (at 91.44 224.79 0)
      (effects (font (size 1.27 1.27) (thickness 0.15)) (justify left bottom) hide)
    )
    (property "License" "Apache-2.0" (at 91.44 227.33 0)
      (effects (font (size 1.27 1.27) (thickness 0.15)) (justify left bottom) hide)
    )
    (pin "1")
    (pin "10")
    (pin "11")
    (pin "12")
    (pin "13")
    (pin "14")
    (pin "15")
    (pin "16")
    (pin "17")
    (pin "18")
    (pin "19")
    (pin "2")
    (pin "20")
    (pin "3")
    (pin "4")
    (pin "5")
    (pin "6")
    (pin "7")
    (pin "8")
    (pin "9")
    (instances
      (project "data-center-rdimm-ddr4-tester"
        (path ""
          (reference "J2") (unit 1)
        )
      )
    )
  )

  (symbol (lib_id "antmicroResistorsmisc:R_0R_0201") (at 337.185 147.32 180) (unit 1)
    (in_bom yes) (on_board yes) (dnp no)
    (property "Reference" "R104" (at 329.565 146.05 0)
      (effects (font (size 1.524 1.524)))
    )
    (property "Value" "R_0R_0201" (at 316.865 134.62 0)
      (effects (font (size 1.27 1.27) (thickness 0.15)) (justify left bottom) hide)
    )
    (property "Footprint" "antmicro-footprints:R_0201" (at 316.865 132.08 0)
      (effects (font (size 1.27 1.27) (thickness 0.15)) (justify left bottom) hide)
    )
    (property "Datasheet" "https://www.bourns.com/docs/product-datasheets/cr.pdf" (at 316.865 129.54 0)
      (effects (font (size 1.27 1.27) (thickness 0.15)) (justify left bottom) hide)
    )
    (property "Manufacturer" "Bourns" (at 316.865 124.46 0)
      (effects (font (size 1.27 1.27) (thickness 0.15)) (justify left bottom) hide)
    )
    (property "MPN" "CR0201-FX-0R00GLF" (at 316.865 127 0)
      (effects (font (size 1.27 1.27) (thickness 0.15)) (justify left bottom) hide)
    )
    (property "Val" "0R" (at 338.455 146.05 0)
      (effects (font (size 1.27 1.27) (thickness 0.15)))
    )
    (property "License" "Apache-2.0" (at 316.865 121.92 0)
      (effects (font (size 1.27 1.27) (thickness 0.15)) (justify left bottom) hide)
    )
    (property "Author" "Antmicro" (at 316.865 119.38 0)
      (effects (font (size 1.27 1.27) (thickness 0.15)) (justify left bottom) hide)
    )
    (property "Tolerance" "1%" (at 316.865 137.16 0)
      (effects (font (size 1.27 1.27)) (justify left bottom) hide)
    )
    (pin "1")
    (pin "2")
    (instances
      (project "data-center-rdimm-ddr4-tester"
        (path ""
          (reference "R104") (unit 1)
        )
      )
    )
  )

  (symbol (lib_id "antmicroCapacitorsmisc:C_47u_16V_1206") (at 381.635 206.375 270) (unit 1)
    (in_bom yes) (on_board yes) (dnp no)
    (property "Reference" "C228" (at 380.365 201.93 0)
      (effects (font (size 1.524 1.524)) (justify left))
    )
    (property "Value" "C_47u_16V_1206" (at 371.475 226.695 0)
      (effects (font (size 1.27 1.27) (thickness 0.15)) (justify left bottom) hide)
    )
    (property "Footprint" "antmicro-footprints:C_1206_3216Metric" (at 368.935 226.695 0)
      (effects (font (size 1.27 1.27) (thickness 0.15)) (justify left bottom) hide)
    )
    (property "Datasheet" " " (at 366.395 226.695 0)
      (effects (font (size 1.27 1.27) (thickness 0.15)) (justify left bottom) hide)
    )
    (property "Manufacturer" "TDK" (at 361.315 226.695 0)
      (effects (font (size 1.27 1.27) (thickness 0.15)) (justify left bottom) hide)
    )
    (property "MPN" "C3216X5R1C476M160AB" (at 363.855 226.695 0)
      (effects (font (size 1.27 1.27) (thickness 0.15)) (justify left bottom) hide)
    )
    (property "Val" "47u/16V" (at 382.905 199.39 0)
      (effects (font (size 1.27 1.27) (thickness 0.15)) (justify left))
    )
    (property "License" "Apache-2.0" (at 358.775 226.695 0)
      (effects (font (size 1.27 1.27) (thickness 0.15)) (justify left bottom) hide)
    )
    (property "Author" "Antmicro" (at 356.235 226.695 0)
      (effects (font (size 1.27 1.27) (thickness 0.15)) (justify left bottom) hide)
    )
    (property "Voltage" "" (at 353.695 226.695 0)
      (effects (font (size 1.27 1.27)) (justify left bottom) hide)
    )
    (property "Dielectric" "" (at 351.155 226.695 0)
      (effects (font (size 1.27 1.27)) (justify left bottom) hide)
    )
    (pin "1")
    (pin "2")
    (instances
      (project "data-center-rdimm-ddr4-tester"
        (path ""
          (reference "C228") (unit 1)
        )
      )
    )
  )

  (symbol (lib_id "antmicroResistors0402:R_0R_0402") (at 312.42 30.48 0) (unit 1)
    (in_bom yes) (on_board yes) (dnp no)
    (property "Reference" "R205" (at 309.88 29.21 0)
      (effects (font (size 1.524 1.524)))
    )
    (property "Value" "R_0R_0402" (at 332.74 43.18 0)
      (effects (font (size 1.27 1.27) (thickness 0.15)) (justify left bottom) hide)
    )
    (property "Footprint" "antmicro-footprints:R_0402_1005Metric" (at 332.74 45.72 0)
      (effects (font (size 1.27 1.27) (thickness 0.15)) (justify left bottom) hide)
    )
    (property "Datasheet" "https://industrial.panasonic.com/cdbs/www-data/pdf/RDA0000/AOA0000C301.pdf" (at 332.74 48.26 0)
      (effects (font (size 1.27 1.27) (thickness 0.15)) (justify left bottom) hide)
    )
    (property "Manufacturer" "Panasonic" (at 332.74 53.34 0)
      (effects (font (size 1.27 1.27) (thickness 0.15)) (justify left bottom) hide)
    )
    (property "MPN" "ERJ2GE0R00X" (at 332.74 50.8 0)
      (effects (font (size 1.27 1.27) (thickness 0.15)) (justify left bottom) hide)
    )
    (property "Val" "0R" (at 318.77 29.21 0)
      (effects (font (size 1.27 1.27) (thickness 0.15)))
    )
    (property "License" "Apache-2.0" (at 332.74 55.88 0)
      (effects (font (size 1.27 1.27) (thickness 0.15)) (justify left bottom) hide)
    )
    (property "Author" "Antmicro" (at 332.74 58.42 0)
      (effects (font (size 1.27 1.27) (thickness 0.15)) (justify left bottom) hide)
    )
    (property "Tolerance" "~" (at 332.74 40.64 0)
      (effects (font (size 1.27 1.27)) (justify left bottom) hide)
    )
    (property "Current" "1A" (at 332.74 60.96 0)
      (effects (font (size 1.27 1.27) (thickness 0.15)) (justify left bottom) hide)
    )
    (pin "1")
    (pin "2")
    (instances
      (project "data-center-rdimm-ddr4-tester"
        (path ""
          (reference "R205") (unit 1)
        )
      )
    )
  )

  (symbol (lib_id "antmicroResistors0603:R_1k3_0603") (at 220.345 232.41 0) (unit 1)
    (in_bom yes) (on_board yes) (dnp no)
    (property "Reference" "R156" (at 217.805 231.14 0)
      (effects (font (size 1.524 1.524)))
    )
    (property "Value" "R_1k3_0603" (at 240.665 245.11 0)
      (effects (font (size 1.27 1.27) (thickness 0.15)) (justify left bottom) hide)
    )
    (property "Footprint" "antmicro-footprints:R_0603_1608Metric" (at 240.665 247.65 0)
      (effects (font (size 1.27 1.27) (thickness 0.15)) (justify left bottom) hide)
    )
    (property "Datasheet" "https://www.bourns.com/docs/product-datasheets/cr.pdf" (at 240.665 250.19 0)
      (effects (font (size 1.27 1.27) (thickness 0.15)) (justify left bottom) hide)
    )
    (property "Manufacturer" "Bourns" (at 240.665 255.27 0)
      (effects (font (size 1.27 1.27) (thickness 0.15)) (justify left bottom) hide)
    )
    (property "MPN" "CR0603-FX-1301ELF" (at 240.665 252.73 0)
      (effects (font (size 1.27 1.27) (thickness 0.15)) (justify left bottom) hide)
    )
    (property "Val" "1k3" (at 227.33 231.14 0)
      (effects (font (size 1.27 1.27) (thickness 0.15)))
    )
    (property "License" "Apache-2.0" (at 240.665 257.81 0)
      (effects (font (size 1.27 1.27) (thickness 0.15)) (justify left bottom) hide)
    )
    (property "Author" "Antmicro" (at 240.665 260.35 0)
      (effects (font (size 1.27 1.27) (thickness 0.15)) (justify left bottom) hide)
    )
    (property "Tolerance" "1%" (at 240.665 242.57 0)
      (effects (font (size 1.27 1.27)) (justify left bottom) hide)
    )
    (pin "1")
    (pin "2")
    (instances
      (project "data-center-rdimm-ddr4-tester"
        (path ""
          (reference "R156") (unit 1)
        )
      )
    )
  )

  (symbol (lib_id "antmicroResistors0402:R_10k_0402") (at 281.305 207.01 90) (unit 1)
    (in_bom no) (on_board yes) (dnp yes)
    (property "Reference" "R182" (at 281.94 201.295 90)
      (effects (font (size 1.524 1.524)) (justify right))
    )
    (property "Value" "R_10k_0402" (at 294.005 186.69 0)
      (effects (font (size 1.27 1.27) (thickness 0.15)) (justify left bottom) hide)
    )
    (property "Footprint" "antmicro-footprints:R_0402_1005Metric" (at 296.545 186.69 0)
      (effects (font (size 1.27 1.27) (thickness 0.15)) (justify left bottom) hide)
    )
    (property "Datasheet" "https://www.bourns.com/docs/product-datasheets/cr.pdf" (at 299.085 186.69 0)
      (effects (font (size 1.27 1.27) (thickness 0.15)) (justify left bottom) hide)
    )
    (property "Manufacturer" "Bourns" (at 304.165 186.69 0)
      (effects (font (size 1.27 1.27) (thickness 0.15)) (justify left bottom) hide)
    )
    (property "MPN" "CR0402-FX-1002GLF" (at 301.625 186.69 0)
      (effects (font (size 1.27 1.27) (thickness 0.15)) (justify left bottom) hide)
    )
    (property "Val" "10k" (at 281.94 207.645 90)
      (effects (font (size 1.27 1.27) (thickness 0.15)) (justify right))
    )
    (property "License" "Apache-2.0" (at 306.705 186.69 0)
      (effects (font (size 1.27 1.27) (thickness 0.15)) (justify left bottom) hide)
    )
    (property "Author" "Antmicro" (at 309.245 186.69 0)
      (effects (font (size 1.27 1.27) (thickness 0.15)) (justify left bottom) hide)
    )
    (property "Tolerance" "1%" (at 291.465 186.69 0)
      (effects (font (size 1.27 1.27)) (justify left bottom) hide)
    )
    (property "DNP" "DNP" (at 281.305 204.47 0)
      (effects (font (size 1.27 1.27)))
    )
    (pin "1")
    (pin "2")
    (instances
      (project "data-center-rdimm-ddr4-tester"
        (path ""
          (reference "R182") (unit 1)
        )
      )
    )
  )

  (symbol (lib_id "antmicroResistors0402:R_10k_0402") (at 180.34 149.86 0) (unit 1)
    (in_bom yes) (on_board yes) (dnp no)
    (property "Reference" "R76" (at 178.435 148.59 0)
      (effects (font (size 1.524 1.524)))
    )
    (property "Value" "R_10k_0402" (at 200.66 162.56 0)
      (effects (font (size 1.27 1.27) (thickness 0.15)) (justify left bottom) hide)
    )
    (property "Footprint" "antmicro-footprints:R_0402_1005Metric" (at 200.66 165.1 0)
      (effects (font (size 1.27 1.27) (thickness 0.15)) (justify left bottom) hide)
    )
    (property "Datasheet" "https://www.bourns.com/docs/product-datasheets/cr.pdf" (at 200.66 167.64 0)
      (effects (font (size 1.27 1.27) (thickness 0.15)) (justify left bottom) hide)
    )
    (property "Manufacturer" "Bourns" (at 200.66 172.72 0)
      (effects (font (size 1.27 1.27) (thickness 0.15)) (justify left bottom) hide)
    )
    (property "MPN" "CR0402-FX-1002GLF" (at 200.66 170.18 0)
      (effects (font (size 1.27 1.27) (thickness 0.15)) (justify left bottom) hide)
    )
    (property "Val" "10k" (at 187.325 148.59 0)
      (effects (font (size 1.27 1.27) (thickness 0.15)))
    )
    (property "License" "Apache-2.0" (at 200.66 175.26 0)
      (effects (font (size 1.27 1.27) (thickness 0.15)) (justify left bottom) hide)
    )
    (property "Author" "Antmicro" (at 200.66 177.8 0)
      (effects (font (size 1.27 1.27) (thickness 0.15)) (justify left bottom) hide)
    )
    (property "Tolerance" "1%" (at 200.66 160.02 0)
      (effects (font (size 1.27 1.27)) (justify left bottom) hide)
    )
    (pin "1")
    (pin "2")
    (instances
      (project "data-center-rdimm-ddr4-tester"
        (path ""
          (reference "R76") (unit 1)
        )
      )
    )
  )
)
